FILE_TYPE = MACRO_DRAWING;
SET COLOR_WIRE YELLOW;
SET COLOR_PROP MONO;
SET COLOR_DOT WHITE;
SET COLOR_ARC YELLOW;
SET COLOR_BODY GREEN;
SET COLOR_NOTE MONO;
SET PROP_DISPLAY VALUE;
SET PAGE_NUMBER P101;
FORCEADD VCC_CORE..1
(-4500 4350);
FORCEPROP 3 LASTPIN (-4500 4300) SIG_NAME P3V3_STBY_MNG\g
J 0
(-4490 4310);
DISPLAY 0.659574 (-4490 4310);
PAINT MONO (-4490 4310);
DISPLAY INVISIBLE (-4490 4310);
FORCEPROP 1 LAST HDL_POWER P3V3_STBY_MNG
J 1
(-4450 4400);
DISPLAY 0.617021 (-4450 4400);
PAINT GREEN (-4450 4400);
FORCEPROP 0 LAST VOLTAGE 5
J 0
(-4500 4350);
PAINT SKYBLUE (-4500 4350);
DISPLAY INVISIBLE (-4500 4350);
FORCEPROP 2 LAST CDS_LIB mstr_symbols
J 0
(-4500 4350);
PAINT ORANGE (-4500 4350);
DISPLAY INVISIBLE (-4500 4350);
FORCEPROP 1 LAST PATH I100
J 0
(-4450 4375);
DISPLAY 0.872340 (-4450 4375);
PAINT AQUA (-4450 4375);
DISPLAY INVISIBLE (-4450 4375);
FORCEADD VCC_CORE..1
(-3625 4275);
FORCEPROP 3 LASTPIN (-3625 4225) SIG_NAME P3V3_STBY_MNG_RGMII\g
J 0
(-3615 4235);
DISPLAY 0.659574 (-3615 4235);
PAINT MONO (-3615 4235);
DISPLAY INVISIBLE (-3615 4235);
FORCEPROP 1 LAST HDL_POWER P3V3_STBY_MNG_RGMII
J 1
(-3575 4325);
DISPLAY 0.617021 (-3575 4325);
PAINT GREEN (-3575 4325);
FORCEPROP 0 LAST VOLTAGE 3.3
J 0
(-3625 4275);
PAINT SKYBLUE (-3625 4275);
DISPLAY INVISIBLE (-3625 4275);
FORCEPROP 2 LAST CDS_LIB mstr_symbols
J 0
(-3625 4275);
PAINT ORANGE (-3625 4275);
DISPLAY INVISIBLE (-3625 4275);
FORCEPROP 1 LAST PATH I101
J 0
(-3575 4300);
DISPLAY 0.872340 (-3575 4300);
PAINT AQUA (-3575 4300);
DISPLAY INVISIBLE (-3575 4300);
FORCEADD VCC_CORE..1
(-3000 4375);
FORCEPROP 3 LASTPIN (-3000 4325) SIG_NAME P3V3_STBY_MNG\g
J 0
(-2990 4335);
DISPLAY 0.659574 (-2990 4335);
PAINT MONO (-2990 4335);
DISPLAY INVISIBLE (-2990 4335);
FORCEPROP 1 LAST HDL_POWER P3V3_STBY_MNG
J 1
(-2950 4425);
DISPLAY 0.617021 (-2950 4425);
PAINT GREEN (-2950 4425);
FORCEPROP 1 LAST PATH I102
J 0
(-2950 4400);
DISPLAY 0.872340 (-2950 4400);
PAINT AQUA (-2950 4400);
DISPLAY INVISIBLE (-2950 4400);
FORCEPROP 2 LAST CDS_LIB mstr_symbols
J 0
(-3000 4375);
PAINT ORANGE (-3000 4375);
DISPLAY INVISIBLE (-3000 4375);
FORCEPROP 0 LAST VOLTAGE 5
J 0
(-3000 4375);
PAINT SKYBLUE (-3000 4375);
DISPLAY INVISIBLE (-3000 4375);
FORCEADD VCC_CORE..1
(-1900 4350);
FORCEPROP 3 LASTPIN (-1900 4300) SIG_NAME P3V3_STBY_MNG_RMII\g
J 0
(-1890 4310);
DISPLAY 0.659574 (-1890 4310);
PAINT MONO (-1890 4310);
DISPLAY INVISIBLE (-1890 4310);
FORCEPROP 1 LAST HDL_POWER P3V3_STBY_MNG_RMII
J 1
(-1850 4400);
DISPLAY 0.617021 (-1850 4400);
PAINT GREEN (-1850 4400);
FORCEPROP 1 LAST PATH I103
J 0
(-1850 4375);
DISPLAY 0.872340 (-1850 4375);
PAINT AQUA (-1850 4375);
DISPLAY INVISIBLE (-1850 4375);
FORCEPROP 2 LAST CDS_LIB mstr_symbols
J 0
(-1900 4350);
PAINT ORANGE (-1900 4350);
DISPLAY INVISIBLE (-1900 4350);
FORCEPROP 0 LAST VOLTAGE 3.3
J 0
(-1900 4350);
PAINT SKYBLUE (-1900 4350);
DISPLAY INVISIBLE (-1900 4350);
FORCEADD CAP_A..1
(-5550 3975);
FORCEPROP 1 LAST PACK_TYPE 0402V
J 0
(-5500 3775);
DISPLAY 0.617021 (-5500 3775);
PAINT SKYBLUE (-5500 3775);
FORCEPROP 1 LASTPIN (-5550 3875) $PN 2
J 0
(-5540 3855);
DISPLAY 0.617021 (-5540 3855);
PAINT WHITE (-5540 3855);
FORCEPROP 1 LASTPIN (-5550 4075) $PN 1
J 0
(-5540 4055);
DISPLAY 0.617021 (-5540 4055);
PAINT WHITE (-5540 4055);
FORCEPROP 1 LAST MATERIAL X7R
J 0
(-5500 3875);
DISPLAY 0.617021 (-5500 3875);
PAINT SKYBLUE (-5500 3875);
FORCEPROP 1 LAST VOLTAGE 25V
J 0
(-5500 3975);
DISPLAY 0.617021 (-5500 3975);
PAINT SKYBLUE (-5500 3975);
FORCEPROP 1 LAST TOLERANCE 10%
J 0
(-5500 3925);
DISPLAY 0.617021 (-5500 3925);
PAINT SKYBLUE (-5500 3925);
FORCEPROP 1 LAST VALUE 0.01UF
J 0
(-5500 4025);
DISPLAY 0.617021 (-5500 4025);
PAINT SKYBLUE (-5500 4025);
FORCEPROP 1 LAST PART_NUMBER A36096-045
J 0
(-5500 3825);
DISPLAY 0.617021 (-5500 3825);
PAINT BLUE (-5500 3825);
FORCEPROP 1 LAST LOCATION C2T18
J 0
(-5500 4075);
DISPLAY 0.617021 (-5500 4075);
PAINT AQUA (-5500 4075);
FORCEPROP 2 LAST ROOM SYS_CLOCK
J 0
(-5500 4125);
DISPLAY 1.127660 (-5500 4125);
PAINT WHITE (-5500 4125);
DISPLAY INVISIBLE (-5500 4125);
FORCEPROP 1 LAST PATH I104
J 0
(-5500 4125);
DISPLAY 0.978723 (-5500 4125);
PAINT WHITE (-5500 4125);
DISPLAY INVISIBLE (-5500 4125);
FORCEPROP 2 LAST $SEC 1
J 0
(-5500 4175);
DISPLAY 1.510638 (-5500 4175);
PAINT MONO (-5500 4175);
DISPLAY INVISIBLE (-5500 4175);
FORCEPROP 2 LAST CDS_SEC 1
J 0
(-5500 4175);
DISPLAY 2.276596 (-5500 4175);
PAINT ORANGE (-5500 4175);
DISPLAY INVISIBLE (-5500 4175);
FORCEPROP 2 LAST CDS_LIB dev_discrete
J 0
(-5550 3975);
PAINT ORANGE (-5550 3975);
DISPLAY INVISIBLE (-5550 3975);
FORCEPROP 2 LAST BOM_COST SM_CONTROLLER
J 0
(-5500 4100);
DISPLAY 1.617021 (-5500 4100);
PAINT WHITE (-5500 4100);
DISPLAY INVISIBLE (-5500 4100);
FORCEPROP 2 LAST CDS_LOCATION C2T18
J 0
(-5500 4075);
DISPLAY 0.617021 (-5500 4075);
PAINT AQUA (-5500 4075);
DISPLAY INVISIBLE (-5500 4075);
FORCEADD RES..1
(-5825 4150);
FORCEPROP 1 LAST PART_NUMBER G22026-127
J 0
(-5875 4250);
DISPLAY 0.617021 (-5875 4250);
PAINT BLUE (-5875 4250);
FORCEPROP 1 LAST WATTAGE 1/10W
J 2
(-5850 4000);
DISPLAY 0.617021 (-5850 4000);
PAINT SKYBLUE (-5850 4000);
FORCEPROP 1 LASTPIN (-5925 4150) $PN 1
J 0
(-5913 4162);
DISPLAY 0.617021 (-5913 4162);
PAINT ORANGE (-5913 4162);
FORCEPROP 1 LASTPIN (-5725 4150) $PN 2
J 0
(-5763 4162);
DISPLAY 0.617021 (-5763 4162);
PAINT ORANGE (-5763 4162);
FORCEPROP 1 LAST MATERIAL CHIP
J 0
(-5825 4000);
DISPLAY 0.617021 (-5825 4000);
PAINT SKYBLUE (-5825 4000);
FORCEPROP 1 LAST PACK_TYPE 0603
J 0
(-5700 4050);
DISPLAY 0.617021 (-5700 4050);
PAINT SKYBLUE (-5700 4050);
FORCEPROP 1 LAST TOLERANCE 1.0%
J 0
(-5825 4050);
DISPLAY 0.617021 (-5825 4050);
PAINT SKYBLUE (-5825 4050);
FORCEPROP 1 LAST VALUE 2.2
J 2
(-5850 4050);
DISPLAY 0.617021 (-5850 4050);
PAINT SKYBLUE (-5850 4050);
FORCEPROP 1 LAST LOCATION R2T21
J 0
(-5875 4200);
DISPLAY 0.617021 (-5875 4200);
PAINT AQUA (-5875 4200);
FORCEPROP 2 LAST ROOM SYS_CLOCK
J 0
(-5975 4300);
DISPLAY 1.127660 (-5975 4300);
PAINT WHITE (-5975 4300);
DISPLAY INVISIBLE (-5975 4300);
FORCEPROP 1 LAST PATH I105
J 0
(-5875 4300);
DISPLAY 0.978723 (-5875 4300);
PAINT WHITE (-5875 4300);
DISPLAY INVISIBLE (-5875 4300);
FORCEPROP 2 LAST CDS_LOCATION R2T21
J 0
(-5875 4200);
DISPLAY 0.617021 (-5875 4200);
PAINT AQUA (-5875 4200);
DISPLAY INVISIBLE (-5875 4200);
FORCEPROP 2 LAST SEC 1
J 0
(-5875 4350);
DISPLAY 0.680851 (-5875 4350);
PAINT MONO (-5875 4350);
DISPLAY INVISIBLE (-5875 4350);
FORCEPROP 2 LAST CDS_LIB mstr_discrete
J 0
(-5825 4150);
DISPLAY 2.127660 (-5825 4150);
PAINT ORANGE (-5825 4150);
DISPLAY INVISIBLE (-5825 4150);
FORCEPROP 2 LAST BOM_COST SM_CONTROLLER
J 0
(-5875 4225);
DISPLAY 1.617021 (-5875 4225);
PAINT WHITE (-5875 4225);
DISPLAY INVISIBLE (-5875 4225);
FORCEPROP 2 LAST SEC_TYPE 0603
J 0
(-5875 4350);
DISPLAY 1.021277 (-5875 4350);
PAINT ORANGE (-5875 4350);
DISPLAY INVISIBLE (-5875 4350);
FORCEADD CAP_A..1
(-5150 3975);
FORCEPROP 1 LAST TOLERANCE 10%
J 0
(-5100 3925);
DISPLAY 0.617021 (-5100 3925);
PAINT SKYBLUE (-5100 3925);
FORCEPROP 1 LASTPIN (-5150 3875) $PN 2
J 0
(-5140 3855);
DISPLAY 0.617021 (-5140 3855);
PAINT WHITE (-5140 3855);
FORCEPROP 1 LASTPIN (-5150 4075) $PN 1
J 0
(-5140 4055);
DISPLAY 0.617021 (-5140 4055);
PAINT WHITE (-5140 4055);
FORCEPROP 1 LAST VOLTAGE 6.3V
J 0
(-5100 3975);
DISPLAY 0.617021 (-5100 3975);
PAINT SKYBLUE (-5100 3975);
FORCEPROP 1 LAST VALUE 1.0UF
J 0
(-5100 4025);
DISPLAY 0.617021 (-5100 4025);
PAINT SKYBLUE (-5100 4025);
FORCEPROP 1 LAST LOCATION C2T19
J 0
(-5100 4075);
DISPLAY 0.617021 (-5100 4075);
PAINT AQUA (-5100 4075);
FORCEPROP 1 LAST PART_NUMBER D97712-004
J 0
(-5100 3825);
DISPLAY 0.617021 (-5100 3825);
PAINT BLUE (-5100 3825);
FORCEPROP 1 LAST PACK_TYPE 0402V
J 0
(-5100 3775);
DISPLAY 0.617021 (-5100 3775);
PAINT SKYBLUE (-5100 3775);
FORCEPROP 1 LAST MATERIAL X6S
J 0
(-5100 3875);
DISPLAY 0.617021 (-5100 3875);
PAINT SKYBLUE (-5100 3875);
FORCEPROP 2 LAST ROOM SYS_CLOCK
J 0
(-5100 4125);
DISPLAY 1.127660 (-5100 4125);
PAINT WHITE (-5100 4125);
DISPLAY INVISIBLE (-5100 4125);
FORCEPROP 1 LAST PATH I106
J 0
(-5100 4125);
DISPLAY 0.978723 (-5100 4125);
PAINT WHITE (-5100 4125);
DISPLAY INVISIBLE (-5100 4125);
FORCEPROP 2 LAST $SEC 1
J 0
(-5100 4175);
DISPLAY 1.510638 (-5100 4175);
PAINT MONO (-5100 4175);
DISPLAY INVISIBLE (-5100 4175);
FORCEPROP 2 LAST CDS_SEC 1
J 0
(-5100 4175);
DISPLAY 2.276596 (-5100 4175);
PAINT ORANGE (-5100 4175);
DISPLAY INVISIBLE (-5100 4175);
FORCEPROP 2 LAST CDS_LIB dev_discrete
J 0
(-5150 3975);
PAINT ORANGE (-5150 3975);
DISPLAY INVISIBLE (-5150 3975);
FORCEPROP 2 LAST BOM_COST SM_CONTROLLER
J 0
(-5100 4100);
DISPLAY 1.617021 (-5100 4100);
PAINT WHITE (-5100 4100);
DISPLAY INVISIBLE (-5100 4100);
FORCEPROP 2 LAST CDS_LOCATION C2T19
J 0
(-5100 4075);
DISPLAY 0.617021 (-5100 4075);
PAINT AQUA (-5100 4075);
DISPLAY INVISIBLE (-5100 4075);
FORCEADD GND..1
(-5150 3650);
FORCEPROP 3 LASTPIN (-5150 3700) SIG_NAME GND\g
J 0
(-5140 3710);
DISPLAY 0.659574 (-5140 3710);
PAINT MONO (-5140 3710);
DISPLAY INVISIBLE (-5140 3710);
FORCEPROP 1 LAST HDL_POWER GND
J 0
(-5150 3800);
PAINT GREEN (-5150 3800);
DISPLAY INVISIBLE (-5150 3800);
FORCEPROP 1 LAST BODY_TYPE PLUMBING
J 0
(-5195 3607);
DISPLAY 0.340426 (-5195 3607);
PAINT GREEN (-5195 3607);
DISPLAY INVISIBLE (-5195 3607);
FORCEPROP 2 LAST ROOM SYS_CLOCK
J 0
(-5475 3725);
DISPLAY 1.127660 (-5475 3725);
PAINT WHITE (-5475 3725);
DISPLAY INVISIBLE (-5475 3725);
FORCEPROP 1 LAST PATH I107
J 0
(-5075 3650);
DISPLAY 0.872340 (-5075 3650);
PAINT AQUA (-5075 3650);
DISPLAY INVISIBLE (-5075 3650);
FORCEPROP 2 LAST BOM_COST SM_CONTROLLER
J 0
(-5600 3725);
DISPLAY 1.617021 (-5600 3725);
PAINT WHITE (-5600 3725);
DISPLAY INVISIBLE (-5600 3725);
FORCEPROP 2 LAST CDS_LIB mstr_symbols
J 0
(-5150 3650);
DISPLAY 2.127660 (-5150 3650);
PAINT ORANGE (-5150 3650);
DISPLAY INVISIBLE (-5150 3650);
FORCEPROP 1 LAST SIZE 1B
J 0
(-5075 3600);
DISPLAY 1.127660 (-5075 3600);
PAINT GREEN (-5075 3600);
DISPLAY INVISIBLE (-5075 3600);
FORCEPROP 1 LAST VOLTAGE 0.0V
J 0
(-5195 3607);
DISPLAY 0.340426 (-5195 3607);
PAINT SKYBLUE (-5195 3607);
DISPLAY INVISIBLE (-5195 3607);
FORCEADD GND..1
(-6600 3625);
FORCEPROP 3 LASTPIN (-6600 3675) SIG_NAME GND\g
J 0
(-6590 3685);
DISPLAY 0.659574 (-6590 3685);
PAINT MONO (-6590 3685);
DISPLAY INVISIBLE (-6590 3685);
FORCEPROP 1 LAST HDL_POWER GND
J 0
(-6600 3775);
PAINT GREEN (-6600 3775);
DISPLAY INVISIBLE (-6600 3775);
FORCEPROP 1 LAST BODY_TYPE PLUMBING
J 0
(-6645 3582);
DISPLAY 0.340426 (-6645 3582);
PAINT GREEN (-6645 3582);
DISPLAY INVISIBLE (-6645 3582);
FORCEPROP 2 LAST ROOM SYS_CLOCK
J 0
(-6920 3705);
DISPLAY 1.127660 (-6920 3705);
PAINT WHITE (-6920 3705);
DISPLAY INVISIBLE (-6920 3705);
FORCEPROP 1 LAST PATH I108
J 0
(-6525 3625);
DISPLAY 0.872340 (-6525 3625);
PAINT AQUA (-6525 3625);
DISPLAY INVISIBLE (-6525 3625);
FORCEPROP 1 LAST SIZE 1B
J 0
(-6525 3575);
DISPLAY 1.127660 (-6525 3575);
PAINT GREEN (-6525 3575);
DISPLAY INVISIBLE (-6525 3575);
FORCEPROP 2 LAST CDS_LIB mstr_symbols
J 0
(-6600 3625);
DISPLAY 2.127660 (-6600 3625);
PAINT ORANGE (-6600 3625);
DISPLAY INVISIBLE (-6600 3625);
FORCEPROP 2 LAST BOM_COST SM_CONTROLLER
J 0
(-7045 3705);
DISPLAY 1.617021 (-7045 3705);
PAINT WHITE (-7045 3705);
DISPLAY INVISIBLE (-7045 3705);
FORCEPROP 1 LAST VOLTAGE 0.0V
J 0
(-6645 3582);
DISPLAY 0.340426 (-6645 3582);
PAINT SKYBLUE (-6645 3582);
DISPLAY INVISIBLE (-6645 3582);
FORCEADD CAP_A..1
(-6600 3975);
FORCEPROP 1 LAST PART_NUMBER A36096-030
J 0
(-6550 3825);
DISPLAY 0.617021 (-6550 3825);
PAINT BLUE (-6550 3825);
FORCEPROP 1 LASTPIN (-6600 3875) $PN 2
J 0
(-6590 3855);
DISPLAY 0.617021 (-6590 3855);
PAINT ORANGE (-6590 3855);
FORCEPROP 1 LASTPIN (-6600 4075) $PN 1
J 0
(-6590 4055);
DISPLAY 0.617021 (-6590 4055);
PAINT ORANGE (-6590 4055);
FORCEPROP 1 LAST MATERIAL X7R
J 0
(-6550 3875);
DISPLAY 0.617021 (-6550 3875);
PAINT SKYBLUE (-6550 3875);
FORCEPROP 1 LAST VOLTAGE 16V
J 0
(-6550 3975);
DISPLAY 0.617021 (-6550 3975);
PAINT SKYBLUE (-6550 3975);
FORCEPROP 1 LAST TOLERANCE 10%
J 0
(-6550 3925);
DISPLAY 0.617021 (-6550 3925);
PAINT SKYBLUE (-6550 3925);
FORCEPROP 1 LAST VALUE 0.1UF
J 0
(-6550 4025);
DISPLAY 0.617021 (-6550 4025);
PAINT SKYBLUE (-6550 4025);
FORCEPROP 1 LAST LOCATION C2T34
J 0
(-6550 4075);
DISPLAY 0.617021 (-6550 4075);
PAINT AQUA (-6550 4075);
FORCEPROP 1 LAST PACK_TYPE 0402V
J 0
(-6550 3775);
DISPLAY 0.617021 (-6550 3775);
PAINT SKYBLUE (-6550 3775);
FORCEPROP 2 LAST SEC 1
J 0
(-6550 4175);
DISPLAY 0.680851 (-6550 4175);
PAINT MONO (-6550 4175);
DISPLAY INVISIBLE (-6550 4175);
FORCEPROP 2 LAST SEC_TYPE 0402V
J 0
(-6550 4175);
DISPLAY 1.021277 (-6550 4175);
PAINT ORANGE (-6550 4175);
DISPLAY INVISIBLE (-6550 4175);
FORCEPROP 2 LAST CDS_SEC 1
J 0
(-6550 4125);
PAINT ORANGE (-6550 4125);
DISPLAY INVISIBLE (-6550 4125);
FORCEPROP 2 LAST CDS_LIB dev_discrete
J 0
(-6600 3975);
PAINT ORANGE (-6600 3975);
DISPLAY INVISIBLE (-6600 3975);
FORCEPROP 2 LAST BOM_COST SM_CONTROLLER
J 0
(-6550 4100);
DISPLAY 1.617021 (-6550 4100);
PAINT WHITE (-6550 4100);
DISPLAY INVISIBLE (-6550 4100);
FORCEPROP 2 LAST CDS_LOCATION C2T34
J 0
(-6550 4075);
DISPLAY 0.617021 (-6550 4075);
PAINT AQUA (-6550 4075);
DISPLAY INVISIBLE (-6550 4075);
FORCEPROP 2 LAST ROOM SYS_CLOCK
J 0
(-6550 4125);
DISPLAY 1.127660 (-6550 4125);
PAINT WHITE (-6550 4125);
DISPLAY INVISIBLE (-6550 4125);
FORCEPROP 1 LAST PATH I109
J 0
(-6550 4125);
DISPLAY 0.978723 (-6550 4125);
PAINT WHITE (-6550 4125);
DISPLAY INVISIBLE (-6550 4125);
FORCEADD CAP_A..1
(-6900 3975);
FORCEPROP 1 LAST LOCATION C2T30
J 0
(-6850 4075);
DISPLAY 0.617021 (-6850 4075);
PAINT AQUA (-6850 4075);
FORCEPROP 1 LAST VALUE 0.1UF
J 0
(-6850 4025);
DISPLAY 0.617021 (-6850 4025);
PAINT SKYBLUE (-6850 4025);
FORCEPROP 1 LASTPIN (-6900 3875) $PN 2
J 0
(-6890 3855);
DISPLAY 0.617021 (-6890 3855);
PAINT WHITE (-6890 3855);
FORCEPROP 1 LASTPIN (-6900 4075) $PN 1
J 0
(-6890 4055);
DISPLAY 0.617021 (-6890 4055);
PAINT WHITE (-6890 4055);
FORCEPROP 1 LAST VOLTAGE 16V
J 0
(-6850 3975);
DISPLAY 0.617021 (-6850 3975);
PAINT SKYBLUE (-6850 3975);
FORCEPROP 1 LAST PACK_TYPE 0402V
J 0
(-6850 3775);
DISPLAY 0.617021 (-6850 3775);
PAINT SKYBLUE (-6850 3775);
FORCEPROP 1 LAST PART_NUMBER A36096-030
J 0
(-6850 3825);
DISPLAY 0.617021 (-6850 3825);
PAINT BLUE (-6850 3825);
FORCEPROP 1 LAST MATERIAL X7R
J 0
(-6850 3875);
DISPLAY 0.617021 (-6850 3875);
PAINT SKYBLUE (-6850 3875);
FORCEPROP 1 LAST TOLERANCE 10%
J 0
(-6850 3925);
DISPLAY 0.617021 (-6850 3925);
PAINT SKYBLUE (-6850 3925);
FORCEPROP 2 LAST $SEC 1
J 0
(-6850 4175);
DISPLAY 1.510638 (-6850 4175);
PAINT MONO (-6850 4175);
DISPLAY INVISIBLE (-6850 4175);
FORCEPROP 2 LAST CDS_SEC 1
J 0
(-6850 4175);
DISPLAY 2.276596 (-6850 4175);
PAINT ORANGE (-6850 4175);
DISPLAY INVISIBLE (-6850 4175);
FORCEPROP 2 LAST CDS_LIB dev_discrete
J 0
(-6900 3975);
PAINT ORANGE (-6900 3975);
DISPLAY INVISIBLE (-6900 3975);
FORCEPROP 2 LAST BOM_COST SM_CONTROLLER
J 0
(-6850 4100);
DISPLAY 1.617021 (-6850 4100);
PAINT WHITE (-6850 4100);
DISPLAY INVISIBLE (-6850 4100);
FORCEPROP 2 LAST CDS_LOCATION C2T30
J 0
(-6850 4075);
DISPLAY 0.617021 (-6850 4075);
PAINT AQUA (-6850 4075);
DISPLAY INVISIBLE (-6850 4075);
FORCEPROP 2 LAST ROOM SYS_CLOCK
J 0
(-6850 4125);
DISPLAY 1.127660 (-6850 4125);
PAINT WHITE (-6850 4125);
DISPLAY INVISIBLE (-6850 4125);
FORCEPROP 1 LAST PATH I110
J 0
(-6850 4125);
DISPLAY 0.978723 (-6850 4125);
PAINT WHITE (-6850 4125);
DISPLAY INVISIBLE (-6850 4125);
FORCEADD CAP_A..1
(-7300 3975);
FORCEPROP 1 LAST PACK_TYPE 0402V
J 0
(-7250 3775);
DISPLAY 0.617021 (-7250 3775);
PAINT SKYBLUE (-7250 3775);
FORCEPROP 1 LASTPIN (-7300 3875) $PN 2
J 0
(-7290 3855);
DISPLAY 0.617021 (-7290 3855);
PAINT WHITE (-7290 3855);
FORCEPROP 1 LASTPIN (-7300 4075) $PN 1
J 0
(-7290 4055);
DISPLAY 0.617021 (-7290 4055);
PAINT WHITE (-7290 4055);
FORCEPROP 1 LAST MATERIAL X7R
J 0
(-7250 3875);
DISPLAY 0.617021 (-7250 3875);
PAINT SKYBLUE (-7250 3875);
FORCEPROP 1 LAST VOLTAGE 16V
J 0
(-7250 3975);
DISPLAY 0.617021 (-7250 3975);
PAINT SKYBLUE (-7250 3975);
FORCEPROP 1 LAST TOLERANCE 10%
J 0
(-7250 3925);
DISPLAY 0.617021 (-7250 3925);
PAINT SKYBLUE (-7250 3925);
FORCEPROP 1 LAST VALUE 0.1UF
J 0
(-7250 4025);
DISPLAY 0.617021 (-7250 4025);
PAINT SKYBLUE (-7250 4025);
FORCEPROP 1 LAST PART_NUMBER A36096-030
J 0
(-7250 3825);
DISPLAY 0.617021 (-7250 3825);
PAINT BLUE (-7250 3825);
FORCEPROP 1 LAST LOCATION C2T25
J 0
(-7250 4075);
DISPLAY 0.617021 (-7250 4075);
PAINT AQUA (-7250 4075);
FORCEPROP 2 LAST $SEC 1
J 0
(-7250 4175);
DISPLAY 1.510638 (-7250 4175);
PAINT MONO (-7250 4175);
DISPLAY INVISIBLE (-7250 4175);
FORCEPROP 2 LAST CDS_SEC 1
J 0
(-7250 4175);
DISPLAY 2.276596 (-7250 4175);
PAINT ORANGE (-7250 4175);
DISPLAY INVISIBLE (-7250 4175);
FORCEPROP 2 LAST CDS_LIB dev_discrete
J 0
(-7300 3975);
PAINT ORANGE (-7300 3975);
DISPLAY INVISIBLE (-7300 3975);
FORCEPROP 2 LAST BOM_COST SM_CONTROLLER
J 0
(-7250 4100);
DISPLAY 1.617021 (-7250 4100);
PAINT WHITE (-7250 4100);
DISPLAY INVISIBLE (-7250 4100);
FORCEPROP 2 LAST CDS_LOCATION C2T25
J 0
(-7250 4075);
DISPLAY 0.617021 (-7250 4075);
PAINT AQUA (-7250 4075);
DISPLAY INVISIBLE (-7250 4075);
FORCEPROP 2 LAST ROOM SYS_CLOCK
J 0
(-7250 4125);
DISPLAY 1.127660 (-7250 4125);
PAINT WHITE (-7250 4125);
DISPLAY INVISIBLE (-7250 4125);
FORCEPROP 1 LAST PATH I111
J 0
(-7250 4125);
DISPLAY 0.978723 (-7250 4125);
PAINT WHITE (-7250 4125);
DISPLAY INVISIBLE (-7250 4125);
FORCEADD CAP_A..1
(-7600 3975);
FORCEPROP 1 LAST PACK_TYPE 0402V
J 0
(-7550 3775);
DISPLAY 0.617021 (-7550 3775);
PAINT SKYBLUE (-7550 3775);
FORCEPROP 1 LASTPIN (-7600 3875) $PN 2
J 0
(-7590 3855);
DISPLAY 0.617021 (-7590 3855);
PAINT WHITE (-7590 3855);
FORCEPROP 1 LASTPIN (-7600 4075) $PN 1
J 0
(-7590 4055);
DISPLAY 0.617021 (-7590 4055);
PAINT WHITE (-7590 4055);
FORCEPROP 1 LAST MATERIAL X7R
J 0
(-7550 3875);
DISPLAY 0.617021 (-7550 3875);
PAINT SKYBLUE (-7550 3875);
FORCEPROP 1 LAST VOLTAGE 16V
J 0
(-7550 3975);
DISPLAY 0.617021 (-7550 3975);
PAINT SKYBLUE (-7550 3975);
FORCEPROP 1 LAST TOLERANCE 10%
J 0
(-7550 3925);
DISPLAY 0.617021 (-7550 3925);
PAINT SKYBLUE (-7550 3925);
FORCEPROP 1 LAST VALUE 0.1UF
J 0
(-7550 4025);
DISPLAY 0.617021 (-7550 4025);
PAINT SKYBLUE (-7550 4025);
FORCEPROP 1 LAST PART_NUMBER A36096-030
J 0
(-7550 3825);
DISPLAY 0.617021 (-7550 3825);
PAINT BLUE (-7550 3825);
FORCEPROP 1 LAST LOCATION C2T17
J 0
(-7550 4075);
DISPLAY 0.617021 (-7550 4075);
PAINT AQUA (-7550 4075);
FORCEPROP 2 LAST $SEC 1
J 0
(-7550 4175);
DISPLAY 1.510638 (-7550 4175);
PAINT MONO (-7550 4175);
DISPLAY INVISIBLE (-7550 4175);
FORCEPROP 2 LAST CDS_SEC 1
J 0
(-7550 4175);
DISPLAY 2.276596 (-7550 4175);
PAINT ORANGE (-7550 4175);
DISPLAY INVISIBLE (-7550 4175);
FORCEPROP 2 LAST CDS_LIB dev_discrete
J 0
(-7600 3975);
PAINT ORANGE (-7600 3975);
DISPLAY INVISIBLE (-7600 3975);
FORCEPROP 2 LAST BOM_COST SM_CONTROLLER
J 0
(-7550 4100);
DISPLAY 1.617021 (-7550 4100);
PAINT WHITE (-7550 4100);
DISPLAY INVISIBLE (-7550 4100);
FORCEPROP 2 LAST CDS_LOCATION C2T17
J 0
(-7550 4075);
DISPLAY 0.617021 (-7550 4075);
PAINT AQUA (-7550 4075);
DISPLAY INVISIBLE (-7550 4075);
FORCEPROP 2 LAST ROOM SYS_CLOCK
J 0
(-7550 4125);
DISPLAY 1.127660 (-7550 4125);
PAINT WHITE (-7550 4125);
DISPLAY INVISIBLE (-7550 4125);
FORCEPROP 1 LAST PATH I112
J 0
(-7550 4125);
DISPLAY 0.978723 (-7550 4125);
PAINT WHITE (-7550 4125);
DISPLAY INVISIBLE (-7550 4125);
FORCEADD CAP..1
(-7900 3975);
FORCEPROP 1 LAST PART_NUMBER C95333-007
J 0
(-7850 3825);
DISPLAY 0.617021 (-7850 3825);
PAINT BLUE (-7850 3825);
FORCEPROP 1 LAST PACK_TYPE 0805
J 0
(-7850 3775);
DISPLAY 0.617021 (-7850 3775);
PAINT SKYBLUE (-7850 3775);
FORCEPROP 1 LAST MATERIAL X6S
J 0
(-7850 3875);
DISPLAY 0.617021 (-7850 3875);
PAINT SKYBLUE (-7850 3875);
FORCEPROP 1 LASTPIN (-7900 4075) $PN 1
J 0
(-7890 4055);
DISPLAY 0.617021 (-7890 4055);
PAINT WHITE (-7890 4055);
FORCEPROP 1 LASTPIN (-7900 3875) $PN 2
J 0
(-7890 3855);
DISPLAY 0.617021 (-7890 3855);
PAINT WHITE (-7890 3855);
FORCEPROP 1 LAST VOLTAGE 16V
J 0
(-7850 3975);
DISPLAY 0.617021 (-7850 3975);
PAINT SKYBLUE (-7850 3975);
FORCEPROP 1 LAST TOLERANCE 10%
J 0
(-7850 3925);
DISPLAY 0.617021 (-7850 3925);
PAINT SKYBLUE (-7850 3925);
FORCEPROP 1 LAST VALUE 10UF
J 0
(-7850 4025);
DISPLAY 0.617021 (-7850 4025);
PAINT SKYBLUE (-7850 4025);
FORCEPROP 1 LAST LOCATION C2T22
J 0
(-7850 4075);
DISPLAY 0.617021 (-7850 4075);
PAINT AQUA (-7850 4075);
FORCEPROP 2 LAST ROOM SYS_CLOCK
J 0
(-7845 4125);
DISPLAY 1.127660 (-7845 4125);
PAINT WHITE (-7845 4125);
DISPLAY INVISIBLE (-7845 4125);
FORCEPROP 1 LAST PATH I113
J 0
(-7850 4125);
DISPLAY 0.978723 (-7850 4125);
PAINT WHITE (-7850 4125);
DISPLAY INVISIBLE (-7850 4125);
FORCEPROP 2 LAST CDS_LOCATION C2T22
J 0
(-7850 4075);
DISPLAY 0.617021 (-7850 4075);
PAINT AQUA (-7850 4075);
DISPLAY INVISIBLE (-7850 4075);
FORCEPROP 2 LAST SEC 1
J 0
(-7845 4175);
DISPLAY 1.510638 (-7845 4175);
PAINT MONO (-7845 4175);
DISPLAY INVISIBLE (-7845 4175);
FORCEPROP 2 LAST SEC_TYPE 0805
J 0
(-7850 4175);
DISPLAY 1.021277 (-7850 4175);
PAINT ORANGE (-7850 4175);
DISPLAY INVISIBLE (-7850 4175);
FORCEPROP 2 LAST BOM_COST SM_CONTROLLER
J 0
(-7845 4100);
DISPLAY 1.617021 (-7845 4100);
PAINT WHITE (-7845 4100);
DISPLAY INVISIBLE (-7845 4100);
FORCEPROP 2 LAST CDS_LIB mstr_discrete
J 0
(-7900 3975);
DISPLAY 1.617021 (-7900 3975);
PAINT ORANGE (-7900 3975);
DISPLAY INVISIBLE (-7900 3975);
FORCEADD FERRITE..1
(-8125 4125);
FORCEPROP 1 LAST PART_NUMBER 656554-043
J 0
(-8220 4240);
DISPLAY 0.617021 (-8220 4240);
PAINT BLUE (-8220 4240);
FORCEPROP 1 LASTPIN (-8225 4125) $PN 1
J 2
(-8190 4135);
DISPLAY 0.617021 (-8190 4135);
PAINT WHITE (-8190 4135);
FORCEPROP 1 LASTPIN (-8025 4125) $PN 2
J 0
(-8045 4135);
DISPLAY 0.617021 (-8045 4135);
PAINT WHITE (-8045 4135);
FORCEPROP 1 LAST MATERIAL FB
J 0
(-8070 4025);
DISPLAY 0.617021 (-8070 4025);
PAINT SKYBLUE (-8070 4025);
FORCEPROP 1 LAST PACK_TYPE SMLF
J 0
(-8195 3975);
DISPLAY 0.617021 (-8195 3975);
PAINT SKYBLUE (-8195 3975);
FORCEPROP 1 LAST VALUE 600
J 2
(-8120 4025);
DISPLAY 0.617021 (-8120 4025);
PAINT SKYBLUE (-8120 4025);
FORCEPROP 1 LAST LOCATION FB2T2
J 0
(-8220 4180);
DISPLAY 0.617021 (-8220 4180);
PAINT AQUA (-8220 4180);
FORCEPROP 2 LAST ROOM SYS_CLOCK
J 0
(-8200 4275);
DISPLAY 1.127660 (-8200 4275);
PAINT WHITE (-8200 4275);
DISPLAY INVISIBLE (-8200 4275);
FORCEPROP 1 LAST PATH I114
J 0
(-8220 4290);
DISPLAY 0.872340 (-8220 4290);
PAINT PURPLE (-8220 4290);
DISPLAY INVISIBLE (-8220 4290);
FORCEPROP 2 LAST CDS_LOCATION FB2T2
J 0
(-8220 4180);
DISPLAY 0.617021 (-8220 4180);
PAINT AQUA (-8220 4180);
DISPLAY INVISIBLE (-8220 4180);
FORCEPROP 2 LAST $SEC 1
J 0
(-8200 4350);
DISPLAY 1.510638 (-8200 4350);
PAINT MONO (-8200 4350);
DISPLAY INVISIBLE (-8200 4350);
FORCEPROP 2 LAST CDS_SEC 1
J 0
(-8200 4350);
DISPLAY 1.659574 (-8200 4350);
PAINT ORANGE (-8200 4350);
DISPLAY INVISIBLE (-8200 4350);
FORCEPROP 2 LAST CDS_LIB mstr_discrete
J 0
(-8125 4125);
DISPLAY 2.127660 (-8125 4125);
PAINT GREEN (-8125 4125);
DISPLAY INVISIBLE (-8125 4125);
FORCEPROP 2 LAST BOM_COST SM_CONTROLLER
J 0
(-8200 4275);
DISPLAY 1.617021 (-8200 4275);
PAINT WHITE (-8200 4275);
DISPLAY INVISIBLE (-8200 4275);
FORCEADD P3V3_STBY..1
(-8475 4350);
FORCEPROP 3 LASTPIN (-8475 4300) SIG_NAME P3V3_STBY\g
J 0
(-8465 4310);
DISPLAY 0.659574 (-8465 4310);
PAINT MONO (-8465 4310);
DISPLAY INVISIBLE (-8465 4310);
FORCEPROP 1 LAST HDL_POWER P3V3_STBY
J 0
(-8775 4225);
DISPLAY 0.872340 (-8775 4225);
PAINT ORANGE (-8775 4225);
DISPLAY INVISIBLE (-8775 4225);
FORCEPROP 1 LAST BODY_TYPE PLUMBING
J 0
(-8520 4307);
DISPLAY 0.340426 (-8520 4307);
PAINT GREEN (-8520 4307);
DISPLAY INVISIBLE (-8520 4307);
FORCEPROP 1 LAST PATH I115
J 0
(-8430 4352);
DISPLAY 0.340426 (-8430 4352);
PAINT GREEN (-8430 4352);
DISPLAY INVISIBLE (-8430 4352);
FORCEPROP 2 LAST CDS_LIB mstr_symbols
J 0
(-8475 4350);
PAINT ORANGE (-8475 4350);
DISPLAY INVISIBLE (-8475 4350);
FORCEPROP 1 LAST SIZE 1B
J 0
(-8430 4372);
DISPLAY 0.340426 (-8430 4372);
PAINT GREEN (-8430 4372);
DISPLAY INVISIBLE (-8430 4372);
FORCEPROP 1 LAST VOLTAGE 3.3
J 0
(-8275 4500);
DISPLAY 1.021277 (-8275 4500);
PAINT SKYBLUE (-8275 4500);
DISPLAY INVISIBLE (-8275 4500);
FORCEADD CAP_A..1
(-8475 3950);
FORCEPROP 1 LAST LOCATION C2T28
J 0
(-8425 4050);
DISPLAY 0.617021 (-8425 4050);
PAINT AQUA (-8425 4050);
FORCEPROP 1 LAST TOLERANCE 10%
J 0
(-8425 3900);
DISPLAY 0.617021 (-8425 3900);
PAINT SKYBLUE (-8425 3900);
FORCEPROP 1 LASTPIN (-8475 3850) $PN 2
J 0
(-8465 3830);
DISPLAY 0.617021 (-8465 3830);
PAINT WHITE (-8465 3830);
FORCEPROP 1 LASTPIN (-8475 4050) $PN 1
J 0
(-8465 4030);
DISPLAY 0.617021 (-8465 4030);
PAINT WHITE (-8465 4030);
FORCEPROP 1 LAST MATERIAL X6S
J 0
(-8425 3850);
DISPLAY 0.617021 (-8425 3850);
PAINT SKYBLUE (-8425 3850);
FORCEPROP 1 LAST VOLTAGE 6.3V
J 0
(-8425 3950);
DISPLAY 0.617021 (-8425 3950);
PAINT SKYBLUE (-8425 3950);
FORCEPROP 1 LAST PACK_TYPE 0402V
J 0
(-8425 3750);
DISPLAY 0.617021 (-8425 3750);
PAINT SKYBLUE (-8425 3750);
FORCEPROP 1 LAST VALUE 1.0UF
J 0
(-8425 4000);
DISPLAY 0.617021 (-8425 4000);
PAINT SKYBLUE (-8425 4000);
FORCEPROP 1 LAST PART_NUMBER D97712-004
J 0
(-8425 3800);
DISPLAY 0.617021 (-8425 3800);
PAINT BLUE (-8425 3800);
FORCEPROP 2 LAST ROOM SYS_CLOCK
J 0
(-8425 4100);
DISPLAY 1.127660 (-8425 4100);
PAINT WHITE (-8425 4100);
DISPLAY INVISIBLE (-8425 4100);
FORCEPROP 1 LAST PATH I116
J 0
(-8425 4100);
DISPLAY 0.978723 (-8425 4100);
PAINT WHITE (-8425 4100);
DISPLAY INVISIBLE (-8425 4100);
FORCEPROP 2 LAST $SEC 1
J 0
(-8425 4150);
DISPLAY 1.510638 (-8425 4150);
PAINT MONO (-8425 4150);
DISPLAY INVISIBLE (-8425 4150);
FORCEPROP 2 LAST CDS_SEC 1
J 0
(-8425 4150);
DISPLAY 1.659574 (-8425 4150);
PAINT ORANGE (-8425 4150);
DISPLAY INVISIBLE (-8425 4150);
FORCEPROP 2 LAST CDS_LIB dev_discrete
J 0
(-8475 3950);
PAINT ORANGE (-8475 3950);
DISPLAY INVISIBLE (-8475 3950);
FORCEPROP 2 LAST BOM_COST SM_CONTROLLER
J 0
(-8425 4075);
DISPLAY 1.617021 (-8425 4075);
PAINT WHITE (-8425 4075);
DISPLAY INVISIBLE (-8425 4075);
FORCEPROP 2 LAST CDS_LOCATION C2T28
J 0
(-8425 4050);
DISPLAY 0.617021 (-8425 4050);
PAINT AQUA (-8425 4050);
DISPLAY INVISIBLE (-8425 4050);
FORCEADD VCC_CORE..1
(-6600 4275);
FORCEPROP 3 LASTPIN (-6600 4225) SIG_NAME P3V3_STBY_MNG\g
J 0
(-6590 4235);
DISPLAY 0.659574 (-6590 4235);
PAINT MONO (-6590 4235);
DISPLAY INVISIBLE (-6590 4235);
FORCEPROP 1 LAST HDL_POWER P3V3_STBY_MNG
J 1
(-6550 4325);
DISPLAY 0.617021 (-6550 4325);
PAINT GREEN (-6550 4325);
FORCEPROP 1 LAST PATH I117
J 0
(-6550 4300);
DISPLAY 0.872340 (-6550 4300);
PAINT AQUA (-6550 4300);
DISPLAY INVISIBLE (-6550 4300);
FORCEPROP 2 LAST CDS_LIB mstr_symbols
J 0
(-6600 4275);
PAINT ORANGE (-6600 4275);
DISPLAY INVISIBLE (-6600 4275);
FORCEPROP 0 LAST VOLTAGE 5
J 0
(-6600 4275);
PAINT SKYBLUE (-6600 4275);
DISPLAY INVISIBLE (-6600 4275);
FORCEADD VCC_CORE..1
(-6100 4350);
FORCEPROP 3 LASTPIN (-6100 4300) SIG_NAME P3V3_STBY_MNG\g
J 0
(-6090 4310);
DISPLAY 0.659574 (-6090 4310);
PAINT MONO (-6090 4310);
DISPLAY INVISIBLE (-6090 4310);
FORCEPROP 1 LAST HDL_POWER P3V3_STBY_MNG
J 1
(-6050 4400);
DISPLAY 0.617021 (-6050 4400);
PAINT GREEN (-6050 4400);
FORCEPROP 1 LAST PATH I118
J 0
(-6050 4375);
DISPLAY 0.872340 (-6050 4375);
PAINT AQUA (-6050 4375);
DISPLAY INVISIBLE (-6050 4375);
FORCEPROP 2 LAST CDS_LIB mstr_symbols
J 0
(-6100 4350);
PAINT ORANGE (-6100 4350);
DISPLAY INVISIBLE (-6100 4350);
FORCEPROP 0 LAST VOLTAGE 5
J 0
(-6100 4350);
PAINT SKYBLUE (-6100 4350);
DISPLAY INVISIBLE (-6100 4350);
FORCEADD VCC_CORE..1
(-6300 3225);
FORCEPROP 3 LASTPIN (-6300 3175) SIG_NAME P3V3_STBY_MNG_RGMII\g
J 0
(-6290 3185);
DISPLAY 0.659574 (-6290 3185);
PAINT MONO (-6290 3185);
DISPLAY INVISIBLE (-6290 3185);
FORCEPROP 1 LAST HDL_POWER P3V3_STBY_MNG_RGMII
J 1
(-6250 3275);
DISPLAY 0.617021 (-6250 3275);
PAINT GREEN (-6250 3275);
FORCEPROP 1 LAST PATH I119
J 0
(-6250 3250);
DISPLAY 0.872340 (-6250 3250);
PAINT AQUA (-6250 3250);
DISPLAY INVISIBLE (-6250 3250);
FORCEPROP 2 LAST CDS_LIB mstr_symbols
J 0
(-6300 3225);
PAINT ORANGE (-6300 3225);
DISPLAY INVISIBLE (-6300 3225);
FORCEPROP 0 LAST VOLTAGE 3.3
J 0
(-6300 3225);
PAINT SKYBLUE (-6300 3225);
DISPLAY INVISIBLE (-6300 3225);
FORCEADD VCC_CORE..1
(-6600 3025);
FORCEPROP 3 LASTPIN (-6600 2975) SIG_NAME P3V3_STBY_MNG_RMII\g
J 0
(-6590 2985);
DISPLAY 0.659574 (-6590 2985);
PAINT MONO (-6590 2985);
DISPLAY INVISIBLE (-6590 2985);
FORCEPROP 1 LAST HDL_POWER P3V3_STBY_MNG_RMII
J 1
(-6550 3075);
DISPLAY 0.617021 (-6550 3075);
PAINT GREEN (-6550 3075);
FORCEPROP 1 LAST PATH I120
J 0
(-6550 3050);
DISPLAY 0.872340 (-6550 3050);
PAINT AQUA (-6550 3050);
DISPLAY INVISIBLE (-6550 3050);
FORCEPROP 2 LAST CDS_LIB mstr_symbols
J 0
(-6600 3025);
PAINT ORANGE (-6600 3025);
DISPLAY INVISIBLE (-6600 3025);
FORCEPROP 0 LAST VOLTAGE 3.3
J 0
(-6600 3025);
PAINT SKYBLUE (-6600 3025);
DISPLAY INVISIBLE (-6600 3025);
FORCEADD VCC_CORE..1
(-5150 4300);
FORCEPROP 3 LASTPIN (-5150 4250) SIG_NAME P3V3_STBY_MNG_CPU\g
J 0
(-5140 4260);
DISPLAY 0.659574 (-5140 4260);
PAINT MONO (-5140 4260);
DISPLAY INVISIBLE (-5140 4260);
FORCEPROP 1 LAST HDL_POWER P3V3_STBY_MNG_CPU
J 1
(-5100 4350);
DISPLAY 0.617021 (-5100 4350);
PAINT GREEN (-5100 4350);
FORCEPROP 1 LAST PATH I121
J 0
(-5100 4325);
DISPLAY 0.872340 (-5100 4325);
PAINT AQUA (-5100 4325);
DISPLAY INVISIBLE (-5100 4325);
FORCEPROP 2 LAST CDS_LIB mstr_symbols
J 0
(-5150 4300);
PAINT ORANGE (-5150 4300);
DISPLAY INVISIBLE (-5150 4300);
FORCEPROP 0 LAST VOLTAGE 3.3
J 0
(-5150 4300);
PAINT SKYBLUE (-5150 4300);
DISPLAY INVISIBLE (-5150 4300);
FORCEADD VCC_CORE..1
(-7000 2525);
FORCEPROP 3 LASTPIN (-7000 2475) SIG_NAME P3V3_STBY_MNG\g
J 0
(-6990 2485);
DISPLAY 0.659574 (-6990 2485);
PAINT MONO (-6990 2485);
DISPLAY INVISIBLE (-6990 2485);
FORCEPROP 1 LAST HDL_POWER P3V3_STBY_MNG
J 1
(-6950 2575);
DISPLAY 0.617021 (-6950 2575);
PAINT GREEN (-6950 2575);
FORCEPROP 1 LAST PATH I122
J 0
(-6950 2550);
DISPLAY 0.872340 (-6950 2550);
PAINT AQUA (-6950 2550);
DISPLAY INVISIBLE (-6950 2550);
FORCEPROP 2 LAST CDS_LIB mstr_symbols
J 0
(-7000 2525);
PAINT ORANGE (-7000 2525);
DISPLAY INVISIBLE (-7000 2525);
FORCEPROP 0 LAST VOLTAGE 5
J 0
(-7000 2525);
PAINT SKYBLUE (-7000 2525);
DISPLAY INVISIBLE (-7000 2525);
FORCEADD VCC_CORE..1
(-7500 2400);
FORCEPROP 3 LASTPIN (-7500 2350) SIG_NAME P3V3_STBY_MNG_CPU\g
J 0
(-7490 2360);
DISPLAY 0.659574 (-7490 2360);
PAINT MONO (-7490 2360);
DISPLAY INVISIBLE (-7490 2360);
FORCEPROP 1 LAST HDL_POWER P3V3_STBY_MNG_CPU
J 1
(-7450 2450);
DISPLAY 0.617021 (-7450 2450);
PAINT GREEN (-7450 2450);
FORCEPROP 1 LAST PATH I123
J 0
(-7450 2425);
DISPLAY 0.872340 (-7450 2425);
PAINT AQUA (-7450 2425);
DISPLAY INVISIBLE (-7450 2425);
FORCEPROP 2 LAST CDS_LIB mstr_symbols
J 0
(-7500 2400);
PAINT ORANGE (-7500 2400);
DISPLAY INVISIBLE (-7500 2400);
FORCEPROP 0 LAST VOLTAGE 3.3
J 0
(-7500 2400);
PAINT SKYBLUE (-7500 2400);
DISPLAY INVISIBLE (-7500 2400);
FORCEADD RES..1
(-3050 1550);
FORCEPROP 1 LAST TOLERANCE 1.0%
J 1
(-3150 1500);
DISPLAY 0.617021 (-3150 1500);
PAINT SKYBLUE (-3150 1500);
FORCEPROP 1 LAST PART_NUMBER G21796-250
J 0
(-2850 1500);
DISPLAY 0.617021 (-2850 1500);
PAINT BLUE (-2850 1500);
FORCEPROP 1 LASTPIN (-3150 1550) $PN 1
J 0
(-3138 1562);
DISPLAY 0.617021 (-3138 1562);
PAINT ORANGE (-3138 1562);
FORCEPROP 1 LAST WATTAGE 1/16W
J 0
(-3100 1500);
DISPLAY 0.617021 (-3100 1500);
PAINT SKYBLUE (-3100 1500);
FORCEPROP 1 LASTPIN (-2950 1550) $PN 2
J 0
(-2988 1562);
DISPLAY 0.617021 (-2988 1562);
PAINT ORANGE (-2988 1562);
FORCEPROP 1 LAST PACK_TYPE 0402
J 0
(-2950 1500);
DISPLAY 0.617021 (-2950 1500);
PAINT SKYBLUE (-2950 1500);
FORCEPROP 1 LAST VALUE 22.1
J 2
(-3150 1575);
DISPLAY 0.617021 (-3150 1575);
PAINT SKYBLUE (-3150 1575);
FORCEPROP 1 LAST LOCATION R2T42
J 1
(-3050 1575);
DISPLAY 0.617021 (-3050 1575);
PAINT AQUA (-3050 1575);
FORCEPROP 1 LAST MATERIAL CHIP
J 0
(-3325 1500);
DISPLAY 0.617021 (-3325 1500);
PAINT SKYBLUE (-3325 1500);
FORCEPROP 0 LAST ROOM SYS_CLOCK
J 0
(-3100 1750);
DISPLAY 1.021277 (-3100 1750);
PAINT ORANGE (-3100 1750);
DISPLAY INVISIBLE (-3100 1750);
FORCEPROP 1 LAST PATH I124
J 0
(-3100 1700);
DISPLAY 0.978723 (-3100 1700);
PAINT WHITE (-3100 1700);
DISPLAY INVISIBLE (-3100 1700);
FORCEPROP 2 LAST CDS_LOCATION R2T42
J 1
(-3050 1575);
DISPLAY 0.617021 (-3050 1575);
PAINT AQUA (-3050 1575);
DISPLAY INVISIBLE (-3050 1575);
FORCEPROP 2 LAST SEC 1
J 0
(-3100 1750);
DISPLAY 0.680851 (-3100 1750);
PAINT MONO (-3100 1750);
DISPLAY INVISIBLE (-3100 1750);
FORCEPROP 2 LAST SEC_TYPE 0402
J 0
(-3100 1750);
DISPLAY 1.021277 (-3100 1750);
PAINT ORANGE (-3100 1750);
DISPLAY INVISIBLE (-3100 1750);
FORCEPROP 2 LAST CDS_LIB mstr_discrete
J 0
(-3050 1550);
PAINT ORANGE (-3050 1550);
DISPLAY INVISIBLE (-3050 1550);
FORCEPROP 0 LAST BOM_COST SM_CONTROLLER
J 0
(-3100 1850);
DISPLAY 1.021277 (-3100 1850);
PAINT ORANGE (-3100 1850);
DISPLAY INVISIBLE (-3100 1850);
FORCEADD RES..1
(-3050 1700);
FORCEPROP 1 LAST LOCATION R2T46
J 1
(-3050 1725);
DISPLAY 0.617021 (-3050 1725);
PAINT AQUA (-3050 1725);
FORCEPROP 1 LASTPIN (-3150 1700) $PN 1
J 0
(-3138 1712);
DISPLAY 0.617021 (-3138 1712);
PAINT ORANGE (-3138 1712);
FORCEPROP 1 LASTPIN (-2950 1700) $PN 2
J 0
(-2988 1712);
DISPLAY 0.617021 (-2988 1712);
PAINT ORANGE (-2988 1712);
FORCEPROP 1 LAST MATERIAL CHIP
J 0
(-3325 1650);
DISPLAY 0.617021 (-3325 1650);
PAINT SKYBLUE (-3325 1650);
FORCEPROP 1 LAST TOLERANCE 1.0%
J 1
(-3150 1650);
DISPLAY 0.617021 (-3150 1650);
PAINT SKYBLUE (-3150 1650);
FORCEPROP 1 LAST PART_NUMBER G21796-250
J 0
(-2850 1650);
DISPLAY 0.617021 (-2850 1650);
PAINT BLUE (-2850 1650);
FORCEPROP 1 LAST WATTAGE 1/16W
J 0
(-3100 1650);
DISPLAY 0.617021 (-3100 1650);
PAINT SKYBLUE (-3100 1650);
FORCEPROP 1 LAST PACK_TYPE 0402
J 0
(-2950 1650);
DISPLAY 0.617021 (-2950 1650);
PAINT SKYBLUE (-2950 1650);
FORCEPROP 1 LAST VALUE 22.1
J 2
(-3150 1725);
DISPLAY 0.617021 (-3150 1725);
PAINT SKYBLUE (-3150 1725);
FORCEPROP 0 LAST ROOM SYS_CLOCK
J 0
(-3100 1900);
DISPLAY 1.021277 (-3100 1900);
PAINT ORANGE (-3100 1900);
DISPLAY INVISIBLE (-3100 1900);
FORCEPROP 2 LAST CDS_LOCATION R2T46
J 1
(-3050 1725);
DISPLAY 0.617021 (-3050 1725);
PAINT AQUA (-3050 1725);
DISPLAY INVISIBLE (-3050 1725);
FORCEPROP 2 LAST SEC 1
J 0
(-3100 1900);
DISPLAY 0.680851 (-3100 1900);
PAINT MONO (-3100 1900);
DISPLAY INVISIBLE (-3100 1900);
FORCEPROP 0 LAST BOM_COST SM_CONTROLLER
J 0
(-3100 2000);
DISPLAY 1.021277 (-3100 2000);
PAINT ORANGE (-3100 2000);
DISPLAY INVISIBLE (-3100 2000);
FORCEPROP 2 LAST CDS_LIB mstr_discrete
J 0
(-3050 1700);
PAINT ORANGE (-3050 1700);
DISPLAY INVISIBLE (-3050 1700);
FORCEPROP 2 LAST SEC_TYPE 0402
J 0
(-3100 1900);
DISPLAY 1.021277 (-3100 1900);
PAINT ORANGE (-3100 1900);
DISPLAY INVISIBLE (-3100 1900);
FORCEPROP 1 LAST PATH I125
J 0
(-3100 1850);
DISPLAY 0.978723 (-3100 1850);
PAINT WHITE (-3100 1850);
DISPLAY INVISIBLE (-3100 1850);
FORCEADD OFFPAGE..2
(-1875 2775);
FORCEPROP 2 LAST $XR0 190 
J 0
(-1686 2775);
DISPLAY 0.638298 (-1686 2775);
PAINT MONO (-1686 2775);
FORCEPROP 1 LAST COMMENT_BODY TRUE
J 0
(-1920 2680);
DISPLAY 1.404255 (-1920 2680);
PAINT PEACH (-1920 2680);
DISPLAY INVISIBLE (-1920 2680);
FORCEPROP 1 LAST OFFPAGE TRUE
J 0
(-1550 2650);
PAINT GREEN (-1550 2650);
DISPLAY INVISIBLE (-1550 2650);
FORCEPROP 2 LAST PATH I13
J 0
(-1550 2825);
DISPLAY 1.021277 (-1550 2825);
PAINT ORANGE (-1550 2825);
DISPLAY INVISIBLE (-1550 2825);
FORCEPROP 2 LAST CDS_LIB mstr_standard
J 0
(-1875 2775);
DISPLAY 1.617021 (-1875 2775);
PAINT MONO (-1875 2775);
DISPLAY INVISIBLE (-1875 2775);
FORCEADD RES..1
(-3050 2600);
FORCEPROP 1 LAST PART_NUMBER G21796-074
J 0
(-2850 2550);
DISPLAY 0.617021 (-2850 2550);
PAINT BLUE (-2850 2550);
FORCEPROP 1 LAST VALUE 33.2
J 2
(-3175 2625);
DISPLAY 0.617021 (-3175 2625);
PAINT SKYBLUE (-3175 2625);
FORCEPROP 1 LAST WATTAGE 1/16W
J 0
(-3100 2550);
DISPLAY 0.617021 (-3100 2550);
PAINT SKYBLUE (-3100 2550);
FORCEPROP 1 LASTPIN (-2950 2600) $PN 2
J 0
(-2988 2612);
DISPLAY 0.617021 (-2988 2612);
PAINT ORANGE (-2988 2612);
FORCEPROP 1 LASTPIN (-3150 2600) $PN 1
J 0
(-3138 2612);
DISPLAY 0.617021 (-3138 2612);
PAINT ORANGE (-3138 2612);
FORCEPROP 1 LAST TOLERANCE 1%
J 1
(-3150 2550);
DISPLAY 0.617021 (-3150 2550);
PAINT SKYBLUE (-3150 2550);
FORCEPROP 1 LAST PACK_TYPE 0402
J 0
(-2950 2550);
DISPLAY 0.617021 (-2950 2550);
PAINT SKYBLUE (-2950 2550);
FORCEPROP 1 LAST LOCATION R2T47
J 0
(-3100 2625);
DISPLAY 0.617021 (-3100 2625);
PAINT AQUA (-3100 2625);
FORCEPROP 1 LAST MATERIAL CHIP
J 0
(-3325 2550);
DISPLAY 0.617021 (-3325 2550);
PAINT SKYBLUE (-3325 2550);
FORCEPROP 1 LAST PATH I130
J 0
(-3100 2750);
DISPLAY 0.978723 (-3100 2750);
PAINT WHITE (-3100 2750);
DISPLAY INVISIBLE (-3100 2750);
FORCEPROP 2 LAST SEC_TYPE 0402
J 0
(-3100 2800);
DISPLAY 1.021277 (-3100 2800);
PAINT ORANGE (-3100 2800);
DISPLAY INVISIBLE (-3100 2800);
FORCEPROP 2 LAST CDS_LIB mstr_discrete
J 0
(-3050 2600);
PAINT ORANGE (-3050 2600);
DISPLAY INVISIBLE (-3050 2600);
FORCEPROP 2 LAST BOM_COST SM_CONTROLLER
J 0
(-3100 2725);
DISPLAY 1.617021 (-3100 2725);
PAINT WHITE (-3100 2725);
DISPLAY INVISIBLE (-3100 2725);
FORCEPROP 2 LAST SEC 1
J 0
(-3100 2800);
PAINT MONO (-3100 2800);
DISPLAY INVISIBLE (-3100 2800);
FORCEPROP 2 LAST CDS_LOCATION R2T47
J 0
(-3100 2625);
DISPLAY 0.617021 (-3100 2625);
PAINT AQUA (-3100 2625);
DISPLAY INVISIBLE (-3100 2625);
FORCEPROP 2 LAST ROOM SYS_CLOCK
J 0
(-3100 2750);
DISPLAY 1.127660 (-3100 2750);
PAINT WHITE (-3100 2750);
DISPLAY INVISIBLE (-3100 2750);
FORCEADD RES..1
(-7125 1950);
FORCEPROP 1 LASTPIN (-7025 1950) $PN 2
J 0
(-7063 1962);
DISPLAY 0.617021 (-7063 1962);
PAINT ORANGE (-7063 1962);
FORCEPROP 1 LAST PART_NUMBER G21497-005
J 0
(-6775 1900);
DISPLAY 0.617021 (-6775 1900);
PAINT BLUE (-6775 1900);
FORCEPROP 1 LAST TOLERANCE 5%
J 0
(-7125 1900);
DISPLAY 0.617021 (-7125 1900);
PAINT SKYBLUE (-7125 1900);
FORCEPROP 1 LASTPIN (-7225 1950) $PN 1
J 0
(-7213 1962);
DISPLAY 0.617021 (-7213 1962);
PAINT ORANGE (-7213 1962);
FORCEPROP 1 LAST WATTAGE 1/16W
J 2
(-7275 1900);
DISPLAY 0.617021 (-7275 1900);
PAINT SKYBLUE (-7275 1900);
FORCEPROP 1 LAST VALUE 0.0
J 2
(-7175 1900);
DISPLAY 0.617021 (-7175 1900);
PAINT SKYBLUE (-7175 1900);
FORCEPROP 1 LAST LOCATION R1W22
J 0
(-7375 1975);
DISPLAY 0.617021 (-7375 1975);
PAINT AQUA (-7375 1975);
FORCEPROP 1 LAST MATERIAL CHIP
J 0
(-7025 1900);
DISPLAY 0.617021 (-7025 1900);
PAINT SKYBLUE (-7025 1900);
FORCEPROP 1 LAST PACK_TYPE 0402
J 0
(-6900 1900);
DISPLAY 0.617021 (-6900 1900);
PAINT SKYBLUE (-6900 1900);
FORCEPROP 1 LAST PATH I134
J 0
(-7175 2100);
DISPLAY 0.978723 (-7175 2100);
PAINT WHITE (-7175 2100);
DISPLAY INVISIBLE (-7175 2100);
FORCEPROP 2 LAST CDS_LIB mstr_discrete
J 0
(-7125 1950);
PAINT ORANGE (-7125 1950);
DISPLAY INVISIBLE (-7125 1950);
FORCEPROP 0 LAST ROOM IO_SLOT
J 0
(-7175 2150);
DISPLAY 1.021277 (-7175 2150);
PAINT ORANGE (-7175 2150);
DISPLAY INVISIBLE (-7175 2150);
FORCEPROP 2 LAST SEC 1
J 0
(-7175 2150);
DISPLAY 0.680851 (-7175 2150);
PAINT MONO (-7175 2150);
DISPLAY INVISIBLE (-7175 2150);
FORCEPROP 2 LAST SEC_TYPE 0402
J 0
(-7175 2150);
DISPLAY 1.021277 (-7175 2150);
PAINT ORANGE (-7175 2150);
DISPLAY INVISIBLE (-7175 2150);
FORCEADD RES..1
(-7125 1825);
FORCEPROP 1 LAST TOLERANCE 5%
J 0
(-7125 1775);
DISPLAY 0.617021 (-7125 1775);
PAINT SKYBLUE (-7125 1775);
FORCEPROP 1 LAST PART_NUMBER G21497-005
J 0
(-6775 1775);
DISPLAY 0.617021 (-6775 1775);
PAINT BLUE (-6775 1775);
FORCEPROP 1 LAST WATTAGE 1/16W
J 2
(-7275 1775);
DISPLAY 0.617021 (-7275 1775);
PAINT SKYBLUE (-7275 1775);
FORCEPROP 1 LASTPIN (-7225 1825) $PN 1
J 0
(-7213 1837);
DISPLAY 0.617021 (-7213 1837);
PAINT ORANGE (-7213 1837);
FORCEPROP 1 LASTPIN (-7025 1825) $PN 2
J 0
(-7063 1837);
DISPLAY 0.617021 (-7063 1837);
PAINT ORANGE (-7063 1837);
FORCEPROP 1 LAST VALUE 0.0
J 2
(-7175 1775);
DISPLAY 0.617021 (-7175 1775);
PAINT SKYBLUE (-7175 1775);
FORCEPROP 1 LAST LOCATION R1W23
J 0
(-7375 1850);
DISPLAY 0.617021 (-7375 1850);
PAINT AQUA (-7375 1850);
FORCEPROP 1 LAST MATERIAL CHIP
J 0
(-7025 1775);
DISPLAY 0.617021 (-7025 1775);
PAINT SKYBLUE (-7025 1775);
FORCEPROP 1 LAST PACK_TYPE 0402
J 0
(-6900 1775);
DISPLAY 0.617021 (-6900 1775);
PAINT SKYBLUE (-6900 1775);
FORCEPROP 1 LAST PATH I135
J 0
(-7175 1975);
DISPLAY 0.978723 (-7175 1975);
PAINT WHITE (-7175 1975);
DISPLAY INVISIBLE (-7175 1975);
FORCEPROP 2 LAST SEC_TYPE 0402
J 0
(-7175 2025);
DISPLAY 1.021277 (-7175 2025);
PAINT ORANGE (-7175 2025);
DISPLAY INVISIBLE (-7175 2025);
FORCEPROP 2 LAST SEC 1
J 0
(-7175 2025);
DISPLAY 0.680851 (-7175 2025);
PAINT MONO (-7175 2025);
DISPLAY INVISIBLE (-7175 2025);
FORCEPROP 0 LAST ROOM IO_SLOT
J 0
(-7175 2025);
DISPLAY 1.021277 (-7175 2025);
PAINT ORANGE (-7175 2025);
DISPLAY INVISIBLE (-7175 2025);
FORCEPROP 2 LAST CDS_LIB mstr_discrete
J 0
(-7125 1825);
PAINT ORANGE (-7125 1825);
DISPLAY INVISIBLE (-7125 1825);
FORCEADD OFFPAGE..1
(-8125 1950);
FORCEPROP 2 LAST $XR5 247 
J 0
(-8977 1950);
DISPLAY 0.638298 (-8977 1950);
PAINT MONO (-8977 1950);
FORCEPROP 2 LAST $XR4 156 
J 0
(-8857 1950);
DISPLAY 0.638298 (-8857 1950);
PAINT MONO (-8857 1950);
FORCEPROP 2 LAST $XR3 111 
J 0
(-8737 1950);
DISPLAY 0.638298 (-8737 1950);
PAINT MONO (-8737 1950);
FORCEPROP 2 LAST $XR2 102 
J 0
(-8617 1950);
DISPLAY 0.638298 (-8617 1950);
PAINT MONO (-8617 1950);
FORCEPROP 2 LAST $XR1 159 
J 0
(-8497 1950);
DISPLAY 0.638298 (-8497 1950);
PAINT MONO (-8497 1950);
FORCEPROP 2 LAST $XR0 138 
J 0
(-8377 1950);
DISPLAY 0.638298 (-8377 1950);
PAINT MONO (-8377 1950);
FORCEPROP 1 LAST COMMENT_BODY TRUE
J 0
(-8000 1850);
DISPLAY 1.404255 (-8000 1850);
PAINT PEACH (-8000 1850);
DISPLAY INVISIBLE (-8000 1850);
FORCEPROP 1 LAST OFFPAGE TRUE
J 0
(-7800 1825);
PAINT GREEN (-7800 1825);
DISPLAY INVISIBLE (-7800 1825);
FORCEPROP 2 LAST CDS_LIB mstr_standard
J 0
(-8125 1950);
DISPLAY 1.617021 (-8125 1950);
PAINT MONO (-8125 1950);
DISPLAY INVISIBLE (-8125 1950);
FORCEPROP 2 LAST PATH I136
J 0
(-8375 2000);
DISPLAY 1.021277 (-8375 2000);
PAINT ORANGE (-8375 2000);
DISPLAY INVISIBLE (-8375 2000);
FORCEADD OFFPAGE..3
R 2
(-8125 1825);
FORCEPROP 2 LAST $XR5 247 
J 0
(-9005 1825);
DISPLAY 0.638298 (-9005 1825);
PAINT MONO (-9005 1825);
FORCEPROP 2 LAST $XR4 159 
J 0
(-8885 1825);
DISPLAY 0.638298 (-8885 1825);
PAINT MONO (-8885 1825);
FORCEPROP 2 LAST $XR3 156 
J 0
(-8765 1825);
DISPLAY 0.638298 (-8765 1825);
PAINT MONO (-8765 1825);
FORCEPROP 2 LAST $XR2 138 
J 0
(-8645 1825);
DISPLAY 0.638298 (-8645 1825);
PAINT MONO (-8645 1825);
FORCEPROP 2 LAST $XR1 111 
J 0
(-8525 1825);
DISPLAY 0.638298 (-8525 1825);
PAINT MONO (-8525 1825);
FORCEPROP 2 LAST $XR0 102 
J 0
(-8405 1825);
DISPLAY 0.638298 (-8405 1825);
PAINT MONO (-8405 1825);
FORCEPROP 1 LAST COMMENT_BODY TRUE
J 2
(-8075 1725);
DISPLAY 0.872340 (-8075 1725);
PAINT GREEN (-8075 1725);
DISPLAY INVISIBLE (-8075 1725);
FORCEPROP 1 LAST OFFPAGE TRUE
J 2
(-8450 1700);
DISPLAY 0.872340 (-8450 1700);
PAINT GREEN (-8450 1700);
DISPLAY INVISIBLE (-8450 1700);
FORCEPROP 2 LAST PATH I137
J 0
(-8425 1875);
DISPLAY 1.021277 (-8425 1875);
PAINT ORANGE (-8425 1875);
DISPLAY INVISIBLE (-8425 1875);
FORCEPROP 2 LAST CDS_LIB mstr_standard
J 2
(-8125 1825);
DISPLAY 1.617021 (-8125 1825);
PAINT MONO (-8125 1825);
DISPLAY INVISIBLE (-8125 1825);
FORCEADD RES..1
(-6925 1250);
FORCEPROP 1 LAST PART_NUMBER G21497-005
J 0
(-6700 1325);
DISPLAY 0.617021 (-6700 1325);
PAINT BLUE (-6700 1325);
FORCEPROP 1 LAST MATERIAL CHIP
J 0
(-6825 1325);
DISPLAY 0.617021 (-6825 1325);
PAINT SKYBLUE (-6825 1325);
FORCEPROP 1 LAST WATTAGE 1/16W
J 2
(-6925 1325);
DISPLAY 0.617021 (-6925 1325);
PAINT SKYBLUE (-6925 1325);
FORCEPROP 1 LASTPIN (-7025 1250) $PN 1
J 0
(-7038 1262);
DISPLAY 0.617021 (-7038 1262);
PAINT ORANGE (-7038 1262);
FORCEPROP 1 LAST PACK_TYPE 0402
J 0
(-6475 1325);
DISPLAY 0.617021 (-6475 1325);
PAINT SKYBLUE (-6475 1325);
FORCEPROP 1 LAST VALUE 0.0
J 2
(-7075 1325);
DISPLAY 0.617021 (-7075 1325);
PAINT SKYBLUE (-7075 1325);
FORCEPROP 1 LAST TOLERANCE 5%
J 0
(-6900 1325);
DISPLAY 0.617021 (-6900 1325);
PAINT SKYBLUE (-6900 1325);
FORCEPROP 1 LAST LOCATION R1W24
J 0
(-7025 1375);
DISPLAY 0.617021 (-7025 1375);
PAINT AQUA (-7025 1375);
FORCEPROP 1 LASTPIN (-6825 1250) $PN 2
J 0
(-6838 1262);
DISPLAY 0.617021 (-6838 1262);
PAINT ORANGE (-6838 1262);
FORCEPROP 2 LAST SEC_TYPE 0402
J 0
(-6975 1450);
DISPLAY 1.021277 (-6975 1450);
PAINT ORANGE (-6975 1450);
DISPLAY INVISIBLE (-6975 1450);
FORCEPROP 2 LAST SEC 1
J 0
(-6975 1450);
DISPLAY 0.680851 (-6975 1450);
PAINT MONO (-6975 1450);
DISPLAY INVISIBLE (-6975 1450);
FORCEPROP 0 LAST ROOM IO_SLOT
J 0
(-6975 1450);
DISPLAY 1.021277 (-6975 1450);
PAINT ORANGE (-6975 1450);
DISPLAY INVISIBLE (-6975 1450);
FORCEPROP 2 LAST CDS_LIB mstr_discrete
J 0
(-6925 1250);
PAINT ORANGE (-6925 1250);
DISPLAY INVISIBLE (-6925 1250);
FORCEPROP 1 LAST PATH I138
J 0
(-6975 1400);
DISPLAY 0.978723 (-6975 1400);
PAINT WHITE (-6975 1400);
DISPLAY INVISIBLE (-6975 1400);
FORCEADD CAP..1
(-1900 4000);
FORCEPROP 1 LASTPIN (-1900 3900) $PN 2
J 0
(-1890 3880);
DISPLAY 0.787234 (-1890 3880);
PAINT ORANGE (-1890 3880);
FORCEPROP 1 LAST MATERIAL EMPTY
J 0
(-1800 3900);
DISPLAY 0.638298 (-1800 3900);
PAINT RED (-1800 3900);
FORCEPROP 1 LAST TOLERANCE 10%
J 0
(-1800 3950);
DISPLAY 0.638298 (-1800 3950);
PAINT SKYBLUE (-1800 3950);
FORCEPROP 1 LAST LOCATION C1W17
J 0
(-1800 4100);
DISPLAY 0.638298 (-1800 4100);
PAINT SKYBLUE (-1800 4100);
FORCEPROP 1 LAST VALUE 10UF
J 0
(-1800 4050);
DISPLAY 0.638298 (-1800 4050);
PAINT SKYBLUE (-1800 4050);
FORCEPROP 1 LAST PACK_TYPE 0805
J 0
(-1800 3800);
DISPLAY 0.638298 (-1800 3800);
PAINT SKYBLUE (-1800 3800);
FORCEPROP 1 LAST VOLTAGE 16V
J 0
(-1800 4000);
DISPLAY 0.638298 (-1800 4000);
PAINT SKYBLUE (-1800 4000);
FORCEPROP 1 LASTPIN (-1900 4100) $PN 1
J 0
(-1890 4080);
DISPLAY 0.787234 (-1890 4080);
PAINT ORANGE (-1890 4080);
FORCEPROP 1 LAST PART_NUMBER C95333-007
J 0
(-1800 3850);
DISPLAY 0.638298 (-1800 3850);
PAINT BLUE (-1800 3850);
FORCEPROP 2 LAST SEC_TYPE 0805
J 0
(-1850 4200);
DISPLAY 1.021277 (-1850 4200);
PAINT ORANGE (-1850 4200);
DISPLAY INVISIBLE (-1850 4200);
FORCEPROP 2 LAST SEC 1
J 0
(-1850 4200);
DISPLAY 0.680851 (-1850 4200);
PAINT MONO (-1850 4200);
DISPLAY INVISIBLE (-1850 4200);
FORCEPROP 2 LAST CDS_LIB mstr_discrete
J 0
(-1900 4000);
PAINT MONO (-1900 4000);
DISPLAY INVISIBLE (-1900 4000);
FORCEPROP 1 LAST PATH I139
J 0
(-1850 4150);
DISPLAY 0.978723 (-1850 4150);
PAINT WHITE (-1850 4150);
DISPLAY INVISIBLE (-1850 4150);
FORCEADD OFFPAGE..2
(-1875 2450);
FORCEPROP 2 LAST $XR0 145 
J 0
(-1686 2450);
DISPLAY 0.638298 (-1686 2450);
PAINT MONO (-1686 2450);
FORCEPROP 1 LAST COMMENT_BODY TRUE
J 0
(-1920 2355);
DISPLAY 1.404255 (-1920 2355);
PAINT PEACH (-1920 2355);
DISPLAY INVISIBLE (-1920 2355);
FORCEPROP 1 LAST OFFPAGE TRUE
J 0
(-1550 2325);
PAINT GREEN (-1550 2325);
DISPLAY INVISIBLE (-1550 2325);
FORCEPROP 2 LAST PATH I14
J 0
(-1675 2500);
DISPLAY 1.021277 (-1675 2500);
PAINT ORANGE (-1675 2500);
DISPLAY INVISIBLE (-1675 2500);
FORCEPROP 2 LAST CDS_LIB mstr_standard
J 0
(-1875 2450);
DISPLAY 1.617021 (-1875 2450);
PAINT MONO (-1875 2450);
DISPLAY INVISIBLE (-1875 2450);
FORCEADD RES..2
(-8325 1400);
FORCEPROP 1 LASTPIN (-8325 1500) $PN 1
J 0
(-8320 1462);
DISPLAY 0.617021 (-8320 1462);
PAINT ORANGE (-8320 1462);
FORCEPROP 1 LASTPIN (-8325 1300) $PN 2
J 0
(-8320 1310);
DISPLAY 0.617021 (-8320 1310);
PAINT ORANGE (-8320 1310);
FORCEPROP 1 LAST WATTAGE 1/16W
J 0
(-8285 1375);
DISPLAY 0.617021 (-8285 1375);
PAINT SKYBLUE (-8285 1375);
FORCEPROP 1 LAST MATERIAL CHIP
J 0
(-8285 1325);
DISPLAY 0.617021 (-8285 1325);
PAINT SKYBLUE (-8285 1325);
FORCEPROP 1 LAST PACK_TYPE 0402
J 0
(-8285 1225);
DISPLAY 0.617021 (-8285 1225);
PAINT SKYBLUE (-8285 1225);
FORCEPROP 1 LAST TOLERANCE 1%
J 0
(-8280 1425);
DISPLAY 0.617021 (-8280 1425);
PAINT SKYBLUE (-8280 1425);
FORCEPROP 1 LAST VALUE 1.00K
J 0
(-8280 1475);
DISPLAY 0.617021 (-8280 1475);
PAINT SKYBLUE (-8280 1475);
FORCEPROP 1 LAST LOCATION R1W25
J 0
(-8280 1525);
DISPLAY 0.617021 (-8280 1525);
PAINT AQUA (-8280 1525);
FORCEPROP 1 LAST PART_NUMBER G21796-026
J 0
(-8285 1275);
DISPLAY 0.617021 (-8285 1275);
PAINT BLUE (-8285 1275);
FORCEPROP 1 LAST PATH I140
J 0
(-8275 1575);
DISPLAY 0.978723 (-8275 1575);
PAINT WHITE (-8275 1575);
DISPLAY INVISIBLE (-8275 1575);
FORCEPROP 2 LAST ROOM SYS_CLOCK
J 2
(-8300 1575);
DISPLAY 1.127660 (-8300 1575);
PAINT WHITE (-8300 1575);
DISPLAY INVISIBLE (-8300 1575);
FORCEPROP 2 LAST SEC 1
J 0
(-8275 1625);
DISPLAY 0.680851 (-8275 1625);
PAINT MONO (-8275 1625);
DISPLAY INVISIBLE (-8275 1625);
FORCEPROP 2 LAST SEC_TYPE 0402
J 0
(-8275 1625);
DISPLAY 1.021277 (-8275 1625);
PAINT ORANGE (-8275 1625);
DISPLAY INVISIBLE (-8275 1625);
FORCEPROP 2 LAST BOM_COST SM_CONTROLLER
J 2
(-8300 1550);
DISPLAY 1.617021 (-8300 1550);
PAINT WHITE (-8300 1550);
DISPLAY INVISIBLE (-8300 1550);
FORCEPROP 2 LAST CDS_LIB mstr_discrete
J 2
(-8325 1400);
DISPLAY 1.617021 (-8325 1400);
PAINT MONO (-8325 1400);
DISPLAY INVISIBLE (-8325 1400);
FORCEPROP 2 LAST CDS_LOCATION R1W25
J 0
(-8280 1525);
DISPLAY 0.617021 (-8280 1525);
PAINT AQUA (-8280 1525);
DISPLAY INVISIBLE (-8280 1525);
FORCEADD GND..1
(-8325 1125);
FORCEPROP 3 LASTPIN (-8325 1175) SIG_NAME GND\g
J 0
(-8315 1185);
DISPLAY 0.659574 (-8315 1185);
PAINT MONO (-8315 1185);
DISPLAY INVISIBLE (-8315 1185);
FORCEPROP 1 LAST HDL_POWER GND
J 0
(-8325 1275);
PAINT GREEN (-8325 1275);
DISPLAY INVISIBLE (-8325 1275);
FORCEPROP 1 LAST BODY_TYPE PLUMBING
J 0
(-8370 1082);
DISPLAY 0.340426 (-8370 1082);
PAINT GREEN (-8370 1082);
DISPLAY INVISIBLE (-8370 1082);
FORCEPROP 2 LAST ROOM SYS_CLOCK
J 0
(-8650 1200);
DISPLAY 1.127660 (-8650 1200);
PAINT WHITE (-8650 1200);
DISPLAY INVISIBLE (-8650 1200);
FORCEPROP 2 LAST BOM_COST SM_CONTROLLER
J 0
(-8775 1200);
DISPLAY 1.617021 (-8775 1200);
PAINT WHITE (-8775 1200);
DISPLAY INVISIBLE (-8775 1200);
FORCEPROP 1 LAST SIZE 1B
J 0
(-8250 1075);
DISPLAY 1.127660 (-8250 1075);
PAINT ORANGE (-8250 1075);
DISPLAY INVISIBLE (-8250 1075);
FORCEPROP 2 LAST CDS_LIB mstr_symbols
J 0
(-8325 1125);
PAINT ORANGE (-8325 1125);
DISPLAY INVISIBLE (-8325 1125);
FORCEPROP 1 LAST VOLTAGE 0.0V
J 0
(-8370 1082);
DISPLAY 0.340426 (-8370 1082);
PAINT SKYBLUE (-8370 1082);
DISPLAY INVISIBLE (-8370 1082);
FORCEPROP 1 LAST PATH I141
J 0
(-8250 1125);
DISPLAY 0.872340 (-8250 1125);
PAINT AQUA (-8250 1125);
DISPLAY INVISIBLE (-8250 1125);
FORCEADD RES..1
(-3050 2775);
FORCEPROP 1 LAST PACK_TYPE 0402
J 0
(-2950 2725);
DISPLAY 0.617021 (-2950 2725);
PAINT SKYBLUE (-2950 2725);
FORCEPROP 1 LASTPIN (-2950 2775) $PN 2
J 0
(-2988 2787);
DISPLAY 0.617021 (-2988 2787);
PAINT ORANGE (-2988 2787);
FORCEPROP 1 LASTPIN (-3150 2775) $PN 1
J 0
(-3138 2787);
DISPLAY 0.617021 (-3138 2787);
PAINT ORANGE (-3138 2787);
FORCEPROP 1 LAST TOLERANCE 1%
J 1
(-3150 2725);
DISPLAY 0.617021 (-3150 2725);
PAINT SKYBLUE (-3150 2725);
FORCEPROP 1 LAST MATERIAL CHIP
J 0
(-3325 2725);
DISPLAY 0.617021 (-3325 2725);
PAINT SKYBLUE (-3325 2725);
FORCEPROP 1 LAST WATTAGE 1/16W
J 0
(-3100 2725);
DISPLAY 0.617021 (-3100 2725);
PAINT SKYBLUE (-3100 2725);
FORCEPROP 1 LAST LOCATION R8F27
J 0
(-3100 2800);
DISPLAY 0.617021 (-3100 2800);
PAINT AQUA (-3100 2800);
FORCEPROP 1 LAST PART_NUMBER G21796-074
J 0
(-2850 2725);
DISPLAY 0.617021 (-2850 2725);
PAINT BLUE (-2850 2725);
FORCEPROP 1 LAST VALUE 33.2
J 2
(-3175 2800);
DISPLAY 0.617021 (-3175 2800);
PAINT SKYBLUE (-3175 2800);
FORCEPROP 2 LAST CDS_LOCATION R8F27
J 0
(-3100 2800);
DISPLAY 0.617021 (-3100 2800);
PAINT AQUA (-3100 2800);
DISPLAY INVISIBLE (-3100 2800);
FORCEPROP 2 LAST SEC_TYPE 0402
J 0
(-3100 2975);
DISPLAY 1.021277 (-3100 2975);
PAINT ORANGE (-3100 2975);
DISPLAY INVISIBLE (-3100 2975);
FORCEPROP 2 LAST CDS_LIB mstr_discrete
J 0
(-3050 2775);
PAINT ORANGE (-3050 2775);
DISPLAY INVISIBLE (-3050 2775);
FORCEPROP 2 LAST BOM_COST SM_CONTROLLER
J 0
(-3100 2900);
DISPLAY 1.617021 (-3100 2900);
PAINT WHITE (-3100 2900);
DISPLAY INVISIBLE (-3100 2900);
FORCEPROP 2 LAST SEC 1
J 0
(-3100 2975);
PAINT MONO (-3100 2975);
DISPLAY INVISIBLE (-3100 2975);
FORCEPROP 2 LAST ROOM SYS_CLOCK
J 0
(-3100 2925);
DISPLAY 1.127660 (-3100 2925);
PAINT WHITE (-3100 2925);
DISPLAY INVISIBLE (-3100 2925);
FORCEPROP 1 LAST PATH I142
J 0
(-3100 2925);
DISPLAY 0.978723 (-3100 2925);
PAINT WHITE (-3100 2925);
DISPLAY INVISIBLE (-3100 2925);
FORCEADD RES..1
(-3050 2150);
FORCEPROP 1 LAST VALUE 22.1
J 2
(-3150 2175);
DISPLAY 0.617021 (-3150 2175);
PAINT SKYBLUE (-3150 2175);
FORCEPROP 1 LAST TOLERANCE 1.0%
J 1
(-3150 2100);
DISPLAY 0.617021 (-3150 2100);
PAINT SKYBLUE (-3150 2100);
FORCEPROP 1 LAST PACK_TYPE 0402
J 0
(-2950 2100);
DISPLAY 0.617021 (-2950 2100);
PAINT SKYBLUE (-2950 2100);
FORCEPROP 1 LASTPIN (-2950 2150) $PN 2
J 0
(-2988 2162);
DISPLAY 0.617021 (-2988 2162);
PAINT ORANGE (-2988 2162);
FORCEPROP 1 LASTPIN (-3150 2150) $PN 1
J 0
(-3138 2162);
DISPLAY 0.617021 (-3138 2162);
PAINT ORANGE (-3138 2162);
FORCEPROP 1 LAST LOCATION R8G24
J 1
(-3050 2175);
DISPLAY 0.617021 (-3050 2175);
PAINT AQUA (-3050 2175);
FORCEPROP 1 LAST WATTAGE 1/16W
J 0
(-3100 2100);
DISPLAY 0.617021 (-3100 2100);
PAINT SKYBLUE (-3100 2100);
FORCEPROP 1 LAST PART_NUMBER G21796-250
J 0
(-2850 2100);
DISPLAY 0.617021 (-2850 2100);
PAINT BLUE (-2850 2100);
FORCEPROP 1 LAST MATERIAL CHIP
J 0
(-3325 2100);
DISPLAY 0.617021 (-3325 2100);
PAINT SKYBLUE (-3325 2100);
FORCEPROP 2 LAST CDS_LOCATION R8G24
J 1
(-3050 2175);
DISPLAY 0.617021 (-3050 2175);
PAINT AQUA (-3050 2175);
DISPLAY INVISIBLE (-3050 2175);
FORCEPROP 2 LAST SEC_TYPE 0402
J 0
(-3100 2350);
DISPLAY 1.021277 (-3100 2350);
PAINT ORANGE (-3100 2350);
DISPLAY INVISIBLE (-3100 2350);
FORCEPROP 2 LAST CDS_LIB mstr_discrete
J 0
(-3050 2150);
PAINT ORANGE (-3050 2150);
DISPLAY INVISIBLE (-3050 2150);
FORCEPROP 0 LAST BOM_COST SM_CONTROLLER
J 0
(-3100 2450);
DISPLAY 1.021277 (-3100 2450);
PAINT ORANGE (-3100 2450);
DISPLAY INVISIBLE (-3100 2450);
FORCEPROP 2 LAST SEC 1
J 0
(-3100 2350);
DISPLAY 0.680851 (-3100 2350);
PAINT MONO (-3100 2350);
DISPLAY INVISIBLE (-3100 2350);
FORCEPROP 0 LAST ROOM SYS_CLOCK
J 0
(-3100 2350);
DISPLAY 1.021277 (-3100 2350);
PAINT ORANGE (-3100 2350);
DISPLAY INVISIBLE (-3100 2350);
FORCEPROP 1 LAST PATH I143
J 0
(-3100 2300);
DISPLAY 0.978723 (-3100 2300);
PAINT WHITE (-3100 2300);
DISPLAY INVISIBLE (-3100 2300);
FORCEADD RES..1
(-3050 2000);
FORCEPROP 1 LAST VALUE 22.1
J 2
(-3150 2025);
DISPLAY 0.617021 (-3150 2025);
PAINT SKYBLUE (-3150 2025);
FORCEPROP 1 LAST TOLERANCE 1.0%
J 1
(-3150 1950);
DISPLAY 0.617021 (-3150 1950);
PAINT SKYBLUE (-3150 1950);
FORCEPROP 1 LAST PACK_TYPE 0402
J 0
(-2950 1950);
DISPLAY 0.617021 (-2950 1950);
PAINT SKYBLUE (-2950 1950);
FORCEPROP 1 LASTPIN (-2950 2000) $PN 2
J 0
(-2988 2012);
DISPLAY 0.617021 (-2988 2012);
PAINT ORANGE (-2988 2012);
FORCEPROP 1 LASTPIN (-3150 2000) $PN 1
J 0
(-3138 2012);
DISPLAY 0.617021 (-3138 2012);
PAINT ORANGE (-3138 2012);
FORCEPROP 1 LAST LOCATION R8G25
J 1
(-3050 2025);
DISPLAY 0.617021 (-3050 2025);
PAINT AQUA (-3050 2025);
FORCEPROP 1 LAST WATTAGE 1/16W
J 0
(-3100 1950);
DISPLAY 0.617021 (-3100 1950);
PAINT SKYBLUE (-3100 1950);
FORCEPROP 1 LAST PART_NUMBER G21796-250
J 0
(-2850 1950);
DISPLAY 0.617021 (-2850 1950);
PAINT BLUE (-2850 1950);
FORCEPROP 1 LAST MATERIAL CHIP
J 0
(-3325 1950);
DISPLAY 0.617021 (-3325 1950);
PAINT SKYBLUE (-3325 1950);
FORCEPROP 0 LAST GROUP NI_I210&RJ45
J 0
(-2938 2047);
DISPLAY 0.638298 (-2938 2047);
PAINT BROWN (-2938 2047);
DISPLAY BOTH (-2938 2047);
FORCEPROP 2 LAST CDS_LOCATION R8G25
J 1
(-3050 2025);
DISPLAY 0.617021 (-3050 2025);
PAINT AQUA (-3050 2025);
DISPLAY INVISIBLE (-3050 2025);
FORCEPROP 2 LAST SEC_TYPE 0402
J 0
(-3100 2200);
DISPLAY 1.021277 (-3100 2200);
PAINT ORANGE (-3100 2200);
DISPLAY INVISIBLE (-3100 2200);
FORCEPROP 2 LAST CDS_LIB mstr_discrete
J 0
(-3050 2000);
PAINT ORANGE (-3050 2000);
DISPLAY INVISIBLE (-3050 2000);
FORCEPROP 0 LAST BOM_COST SM_CONTROLLER
J 0
(-3100 2300);
DISPLAY 1.021277 (-3100 2300);
PAINT ORANGE (-3100 2300);
DISPLAY INVISIBLE (-3100 2300);
FORCEPROP 2 LAST SEC 1
J 0
(-3100 2200);
DISPLAY 0.680851 (-3100 2200);
PAINT MONO (-3100 2200);
DISPLAY INVISIBLE (-3100 2200);
FORCEPROP 0 LAST ROOM SYS_CLOCK
J 0
(-3100 2200);
DISPLAY 1.021277 (-3100 2200);
PAINT ORANGE (-3100 2200);
DISPLAY INVISIBLE (-3100 2200);
FORCEPROP 1 LAST PATH I144
J 0
(-3100 2150);
DISPLAY 0.978723 (-3100 2150);
PAINT WHITE (-3100 2150);
DISPLAY INVISIBLE (-3100 2150);
FORCEADD RES..1
(-3050 1850);
FORCEPROP 1 LAST WATTAGE 1/16W
J 0
(-3100 1800);
DISPLAY 0.617021 (-3100 1800);
PAINT SKYBLUE (-3100 1800);
FORCEPROP 1 LAST TOLERANCE 1.0%
J 1
(-3150 1800);
DISPLAY 0.617021 (-3150 1800);
PAINT SKYBLUE (-3150 1800);
FORCEPROP 1 LAST MATERIAL CHIP
J 0
(-3325 1800);
DISPLAY 0.617021 (-3325 1800);
PAINT SKYBLUE (-3325 1800);
FORCEPROP 1 LASTPIN (-2950 1850) $PN 2
J 0
(-2988 1862);
DISPLAY 0.617021 (-2988 1862);
PAINT ORANGE (-2988 1862);
FORCEPROP 1 LASTPIN (-3150 1850) $PN 1
J 0
(-3138 1862);
DISPLAY 0.617021 (-3138 1862);
PAINT ORANGE (-3138 1862);
FORCEPROP 1 LAST LOCATION R8G1
J 1
(-3050 1875);
DISPLAY 0.617021 (-3050 1875);
PAINT AQUA (-3050 1875);
FORCEPROP 1 LAST PART_NUMBER G21796-250
J 0
(-2850 1800);
DISPLAY 0.617021 (-2850 1800);
PAINT BLUE (-2850 1800);
FORCEPROP 1 LAST PACK_TYPE 0402
J 0
(-2950 1800);
DISPLAY 0.617021 (-2950 1800);
PAINT SKYBLUE (-2950 1800);
FORCEPROP 1 LAST VALUE 22.1
J 2
(-3150 1875);
DISPLAY 0.617021 (-3150 1875);
PAINT SKYBLUE (-3150 1875);
FORCEPROP 2 LAST CDS_LOCATION R8G1
J 1
(-3050 1875);
DISPLAY 0.617021 (-3050 1875);
PAINT AQUA (-3050 1875);
DISPLAY INVISIBLE (-3050 1875);
FORCEPROP 2 LAST SEC_TYPE 0402
J 0
(-3100 2050);
DISPLAY 1.021277 (-3100 2050);
PAINT ORANGE (-3100 2050);
DISPLAY INVISIBLE (-3100 2050);
FORCEPROP 2 LAST CDS_LIB mstr_discrete
J 0
(-3050 1850);
PAINT ORANGE (-3050 1850);
DISPLAY INVISIBLE (-3050 1850);
FORCEPROP 0 LAST BOM_COST SM_CONTROLLER
J 0
(-3100 2150);
DISPLAY 1.021277 (-3100 2150);
PAINT ORANGE (-3100 2150);
DISPLAY INVISIBLE (-3100 2150);
FORCEPROP 2 LAST SEC 1
J 0
(-3100 2050);
DISPLAY 0.680851 (-3100 2050);
PAINT MONO (-3100 2050);
DISPLAY INVISIBLE (-3100 2050);
FORCEPROP 0 LAST ROOM SYS_CLOCK
J 0
(-3100 2050);
DISPLAY 1.021277 (-3100 2050);
PAINT ORANGE (-3100 2050);
DISPLAY INVISIBLE (-3100 2050);
FORCEPROP 1 LAST PATH I145
J 0
(-3100 2000);
DISPLAY 0.978723 (-3100 2000);
PAINT WHITE (-3100 2000);
DISPLAY INVISIBLE (-3100 2000);
FORCEADD CAP..1
(-7600 800);
FORCEPROP 1 LASTPIN (-7600 900) $PN 1
J 0
(-7590 880);
DISPLAY 0.617021 (-7590 880);
PAINT ORANGE (-7590 880);
FORCEPROP 1 LASTPIN (-7600 700) $PN 2
J 0
(-7590 680);
DISPLAY 0.617021 (-7590 680);
PAINT ORANGE (-7590 680);
FORCEPROP 1 LAST MATERIAL COG
J 0
(-7550 700);
DISPLAY 0.617021 (-7550 700);
PAINT SKYBLUE (-7550 700);
FORCEPROP 1 LAST TOLERANCE 5%
J 0
(-7550 750);
DISPLAY 0.617021 (-7550 750);
PAINT SKYBLUE (-7550 750);
FORCEPROP 1 LAST VOLTAGE 50V
J 0
(-7550 800);
DISPLAY 0.617021 (-7550 800);
PAINT SKYBLUE (-7550 800);
FORCEPROP 1 LAST PART_NUMBER A36095-047
J 0
(-7550 650);
DISPLAY 0.617021 (-7550 650);
PAINT BLUE (-7550 650);
FORCEPROP 1 LAST PACK_TYPE 0402LF
J 0
(-7550 600);
DISPLAY 0.617021 (-7550 600);
PAINT SKYBLUE (-7550 600);
FORCEPROP 1 LAST VALUE 15.0PF
J 0
(-7550 850);
DISPLAY 0.617021 (-7550 850);
PAINT SKYBLUE (-7550 850);
FORCEPROP 1 LAST LOCATION C8F19
J 0
(-7550 900);
DISPLAY 0.617021 (-7550 900);
PAINT AQUA (-7550 900);
FORCEPROP 1 LAST PATH I146
J 0
(-7550 950);
DISPLAY 0.978723 (-7550 950);
PAINT WHITE (-7550 950);
DISPLAY INVISIBLE (-7550 950);
FORCEPROP 2 LAST SEC_TYPE 0402LF
J 0
(-7550 1000);
DISPLAY 1.021277 (-7550 1000);
PAINT ORANGE (-7550 1000);
DISPLAY INVISIBLE (-7550 1000);
FORCEPROP 2 LAST SEC 1
J 0
(-7550 1000);
DISPLAY 0.680851 (-7550 1000);
PAINT MONO (-7550 1000);
DISPLAY INVISIBLE (-7550 1000);
FORCEPROP 2 LAST CDS_LIB mstr_discrete
J 0
(-7600 800);
PAINT ORANGE (-7600 800);
DISPLAY INVISIBLE (-7600 800);
FORCEPROP 2 LAST ROOM SB
J 0
(-7600 800);
PAINT MONO (-7600 800);
DISPLAY INVISIBLE (-7600 800);
FORCEPROP 2 LAST BOM_COST SYS_CLOCK
J 0
(-7460 610);
PAINT MONO (-7460 610);
DISPLAY INVISIBLE (-7460 610);
FORCEPROP 2 LAST CDS_LOCATION C8F19
J 0
(-7550 900);
DISPLAY 0.617021 (-7550 900);
PAINT AQUA (-7550 900);
DISPLAY INVISIBLE (-7550 900);
FORCEADD CAP..1
(-7150 800);
FORCEPROP 1 LASTPIN (-7150 700) $PN 2
J 0
(-7140 680);
DISPLAY 0.617021 (-7140 680);
PAINT ORANGE (-7140 680);
FORCEPROP 1 LAST MATERIAL COG
J 0
(-7100 700);
DISPLAY 0.617021 (-7100 700);
PAINT SKYBLUE (-7100 700);
FORCEPROP 1 LAST TOLERANCE 5%
J 0
(-7100 750);
DISPLAY 0.617021 (-7100 750);
PAINT SKYBLUE (-7100 750);
FORCEPROP 1 LAST VOLTAGE 50V
J 0
(-7100 800);
DISPLAY 0.617021 (-7100 800);
PAINT SKYBLUE (-7100 800);
FORCEPROP 1 LAST VALUE 15.0PF
J 0
(-7100 850);
DISPLAY 0.617021 (-7100 850);
PAINT SKYBLUE (-7100 850);
FORCEPROP 1 LAST LOCATION C8F18
J 0
(-7100 900);
DISPLAY 0.617021 (-7100 900);
PAINT AQUA (-7100 900);
FORCEPROP 1 LAST PART_NUMBER A36095-047
J 0
(-7100 650);
DISPLAY 0.617021 (-7100 650);
PAINT BLUE (-7100 650);
FORCEPROP 1 LAST PACK_TYPE 0402LF
J 0
(-7100 600);
DISPLAY 0.617021 (-7100 600);
PAINT SKYBLUE (-7100 600);
FORCEPROP 1 LASTPIN (-7150 900) $PN 1
J 0
(-7140 880);
DISPLAY 0.617021 (-7140 880);
PAINT ORANGE (-7140 880);
FORCEPROP 2 LAST SEC_TYPE 0402LF
J 0
(-7100 1000);
DISPLAY 1.021277 (-7100 1000);
PAINT ORANGE (-7100 1000);
DISPLAY INVISIBLE (-7100 1000);
FORCEPROP 2 LAST SEC 1
J 0
(-7100 1000);
DISPLAY 0.680851 (-7100 1000);
PAINT MONO (-7100 1000);
DISPLAY INVISIBLE (-7100 1000);
FORCEPROP 2 LAST CDS_LIB mstr_discrete
J 0
(-7150 800);
PAINT ORANGE (-7150 800);
DISPLAY INVISIBLE (-7150 800);
FORCEPROP 2 LAST ROOM SB
J 0
(-7150 800);
PAINT MONO (-7150 800);
DISPLAY INVISIBLE (-7150 800);
FORCEPROP 2 LAST BOM_COST SYS_CLOCK
J 0
(-7010 610);
PAINT MONO (-7010 610);
DISPLAY INVISIBLE (-7010 610);
FORCEPROP 1 LAST PATH I147
J 0
(-7100 950);
DISPLAY 0.978723 (-7100 950);
PAINT WHITE (-7100 950);
DISPLAY INVISIBLE (-7100 950);
FORCEPROP 2 LAST CDS_LOCATION C8F18
J 0
(-7100 900);
DISPLAY 0.617021 (-7100 900);
PAINT AQUA (-7100 900);
DISPLAY INVISIBLE (-7100 900);
FORCEADD RES..1
(-3050 2450);
FORCEPROP 1 LAST LOCATION R8F29
J 0
(-3100 2475);
DISPLAY 0.617021 (-3100 2475);
PAINT AQUA (-3100 2475);
FORCEPROP 1 LASTPIN (-3150 2450) $PN 1
J 0
(-3138 2462);
DISPLAY 0.617021 (-3138 2462);
PAINT WHITE (-3138 2462);
FORCEPROP 1 LAST TOLERANCE 1%
J 1
(-3150 2400);
DISPLAY 0.617021 (-3150 2400);
PAINT SKYBLUE (-3150 2400);
FORCEPROP 1 LASTPIN (-2950 2450) $PN 2
J 0
(-2988 2462);
DISPLAY 0.617021 (-2988 2462);
PAINT WHITE (-2988 2462);
FORCEPROP 1 LAST VALUE 33.2
J 2
(-3150 2475);
DISPLAY 0.617021 (-3150 2475);
PAINT SKYBLUE (-3150 2475);
FORCEPROP 1 LAST MATERIAL CHIP
J 0
(-3325 2400);
DISPLAY 0.617021 (-3325 2400);
PAINT SKYBLUE (-3325 2400);
FORCEPROP 1 LAST WATTAGE 1/16W
J 0
(-3100 2400);
DISPLAY 0.617021 (-3100 2400);
PAINT SKYBLUE (-3100 2400);
FORCEPROP 1 LAST PACK_TYPE 0402
J 0
(-2950 2400);
DISPLAY 0.617021 (-2950 2400);
PAINT SKYBLUE (-2950 2400);
FORCEPROP 1 LAST PART_NUMBER G21796-074
J 0
(-2850 2400);
DISPLAY 0.617021 (-2850 2400);
PAINT BLUE (-2850 2400);
FORCEPROP 2 LAST ROOM SYS_CLOCK
J 0
(-3100 2600);
DISPLAY 1.127660 (-3100 2600);
PAINT WHITE (-3100 2600);
DISPLAY INVISIBLE (-3100 2600);
FORCEPROP 1 LAST PATH I20
J 0
(-3100 2600);
DISPLAY 0.978723 (-3100 2600);
PAINT WHITE (-3100 2600);
DISPLAY INVISIBLE (-3100 2600);
FORCEPROP 2 LAST CDS_LOCATION R8F29
J 0
(-3100 2475);
DISPLAY 0.617021 (-3100 2475);
PAINT AQUA (-3100 2475);
DISPLAY INVISIBLE (-3100 2475);
FORCEPROP 2 LAST SEC 1
J 0
(-3100 2650);
DISPLAY 1.510638 (-3100 2650);
PAINT MONO (-3100 2650);
DISPLAY INVISIBLE (-3100 2650);
FORCEPROP 2 LAST CDS_LIB mstr_discrete
J 0
(-3050 2450);
DISPLAY 1.617021 (-3050 2450);
PAINT ORANGE (-3050 2450);
DISPLAY INVISIBLE (-3050 2450);
FORCEPROP 2 LAST SEC_TYPE 0402
J 0
(-3100 2650);
DISPLAY 1.659574 (-3100 2650);
PAINT ORANGE (-3100 2650);
DISPLAY INVISIBLE (-3100 2650);
FORCEPROP 2 LAST BOM_COST SM_CONTROLLER
J 0
(-3100 2575);
DISPLAY 1.617021 (-3100 2575);
PAINT WHITE (-3100 2575);
DISPLAY INVISIBLE (-3100 2575);
FORCEADD RES..2
R 2
(-4375 3000);
FORCEPROP 1 LASTPIN (-4375 3100) $PN 1
J 2
(-4380 3062);
DISPLAY 0.617021 (-4380 3062);
PAINT WHITE (-4380 3062);
FORCEPROP 1 LASTPIN (-4375 2900) $PN 2
J 2
(-4380 2910);
DISPLAY 0.617021 (-4380 2910);
PAINT WHITE (-4380 2910);
FORCEPROP 1 LAST TOLERANCE 1%
J 2
(-4420 3025);
DISPLAY 0.617021 (-4420 3025);
PAINT SKYBLUE (-4420 3025);
FORCEPROP 1 LAST MATERIAL CHIP
J 2
(-4415 2925);
DISPLAY 0.617021 (-4415 2925);
PAINT SKYBLUE (-4415 2925);
FORCEPROP 1 LAST WATTAGE 1/16W
J 2
(-4415 2975);
DISPLAY 0.617021 (-4415 2975);
PAINT SKYBLUE (-4415 2975);
FORCEPROP 1 LAST VALUE 475.0
J 2
(-4420 3075);
DISPLAY 0.617021 (-4420 3075);
PAINT SKYBLUE (-4420 3075);
FORCEPROP 1 LAST LOCATION R8F25
J 2
(-4420 3125);
DISPLAY 0.617021 (-4420 3125);
PAINT AQUA (-4420 3125);
FORCEPROP 1 LAST PART_NUMBER G21796-077
J 2
(-4415 2875);
DISPLAY 0.617021 (-4415 2875);
PAINT BLUE (-4415 2875);
FORCEPROP 1 LAST PACK_TYPE 0402
J 2
(-4415 2825);
DISPLAY 0.617021 (-4415 2825);
PAINT SKYBLUE (-4415 2825);
FORCEPROP 2 LAST ROOM SYS_CLOCK
J 0
(-4400 3175);
DISPLAY 1.127660 (-4400 3175);
PAINT WHITE (-4400 3175);
DISPLAY INVISIBLE (-4400 3175);
FORCEPROP 1 LAST PATH I28
J 2
(-4425 3175);
DISPLAY 0.978723 (-4425 3175);
PAINT WHITE (-4425 3175);
DISPLAY INVISIBLE (-4425 3175);
FORCEPROP 2 LAST CDS_LOCATION R8F25
J 2
(-4420 3125);
DISPLAY 0.617021 (-4420 3125);
PAINT AQUA (-4420 3125);
DISPLAY INVISIBLE (-4420 3125);
FORCEPROP 2 LAST $SEC 1
J 0
(-4425 3225);
DISPLAY 1.510638 (-4425 3225);
PAINT MONO (-4425 3225);
DISPLAY INVISIBLE (-4425 3225);
FORCEPROP 2 LAST CDS_SEC 1
J 0
(-4425 3225);
DISPLAY 2.276596 (-4425 3225);
PAINT ORANGE (-4425 3225);
DISPLAY INVISIBLE (-4425 3225);
FORCEPROP 2 LAST BOM_COST SM_CONTROLLER
J 0
(-4400 3150);
DISPLAY 1.617021 (-4400 3150);
PAINT WHITE (-4400 3150);
DISPLAY INVISIBLE (-4400 3150);
FORCEPROP 2 LAST CDS_LIB mstr_discrete
J 0
(-4375 3000);
DISPLAY 1.617021 (-4375 3000);
PAINT MONO (-4375 3000);
DISPLAY INVISIBLE (-4375 3000);
FORCEADD GND..1
(-4375 2800);
FORCEPROP 3 LASTPIN (-4375 2850) SIG_NAME GND\g
J 0
(-4365 2860);
DISPLAY 0.659574 (-4365 2860);
PAINT MONO (-4365 2860);
DISPLAY INVISIBLE (-4365 2860);
FORCEPROP 1 LAST HDL_POWER GND
J 0
(-4375 2950);
PAINT GREEN (-4375 2950);
DISPLAY INVISIBLE (-4375 2950);
FORCEPROP 1 LAST BODY_TYPE PLUMBING
J 0
(-4420 2757);
DISPLAY 0.340426 (-4420 2757);
PAINT GREEN (-4420 2757);
DISPLAY INVISIBLE (-4420 2757);
FORCEPROP 2 LAST ROOM SYS_CLOCK
J 0
(-4700 2875);
DISPLAY 1.127660 (-4700 2875);
PAINT WHITE (-4700 2875);
DISPLAY INVISIBLE (-4700 2875);
FORCEPROP 1 LAST PATH I29
J 0
(-4300 2800);
DISPLAY 0.872340 (-4300 2800);
PAINT AQUA (-4300 2800);
DISPLAY INVISIBLE (-4300 2800);
FORCEPROP 2 LAST BOM_COST SM_CONTROLLER
J 0
(-4825 2875);
DISPLAY 1.617021 (-4825 2875);
PAINT WHITE (-4825 2875);
DISPLAY INVISIBLE (-4825 2875);
FORCEPROP 1 LAST SIZE 1B
J 0
(-4300 2750);
DISPLAY 1.127660 (-4300 2750);
PAINT ORANGE (-4300 2750);
DISPLAY INVISIBLE (-4300 2750);
FORCEPROP 2 LAST CDS_LIB mstr_symbols
J 0
(-4375 2800);
DISPLAY 1.617021 (-4375 2800);
PAINT MONO (-4375 2800);
DISPLAY INVISIBLE (-4375 2800);
FORCEPROP 1 LAST VOLTAGE 0.0V
J 0
(-4420 2757);
DISPLAY 0.340426 (-4420 2757);
PAINT SKYBLUE (-4420 2757);
DISPLAY INVISIBLE (-4420 2757);
FORCEADD GND..1
(-4650 800);
FORCEPROP 3 LASTPIN (-4650 850) SIG_NAME GND\g
J 0
(-4640 860);
DISPLAY 0.659574 (-4640 860);
PAINT MONO (-4640 860);
DISPLAY INVISIBLE (-4640 860);
FORCEPROP 1 LAST HDL_POWER GND
J 0
(-4650 950);
PAINT GREEN (-4650 950);
DISPLAY INVISIBLE (-4650 950);
FORCEPROP 1 LAST BODY_TYPE PLUMBING
J 0
(-4695 757);
DISPLAY 0.340426 (-4695 757);
PAINT GREEN (-4695 757);
DISPLAY INVISIBLE (-4695 757);
FORCEPROP 2 LAST ROOM SYS_CLOCK
J 0
(-4975 875);
DISPLAY 1.127660 (-4975 875);
PAINT WHITE (-4975 875);
DISPLAY INVISIBLE (-4975 875);
FORCEPROP 1 LAST PATH I33
J 0
(-4575 800);
DISPLAY 0.872340 (-4575 800);
PAINT AQUA (-4575 800);
DISPLAY INVISIBLE (-4575 800);
FORCEPROP 1 LAST SIZE 1B
J 0
(-4575 750);
DISPLAY 1.127660 (-4575 750);
PAINT ORANGE (-4575 750);
DISPLAY INVISIBLE (-4575 750);
FORCEPROP 2 LAST CDS_LIB mstr_symbols
J 0
(-4650 800);
DISPLAY 1.617021 (-4650 800);
PAINT MONO (-4650 800);
DISPLAY INVISIBLE (-4650 800);
FORCEPROP 2 LAST BOM_COST SM_CONTROLLER
J 0
(-5100 875);
DISPLAY 1.617021 (-5100 875);
PAINT WHITE (-5100 875);
DISPLAY INVISIBLE (-5100 875);
FORCEPROP 1 LAST VOLTAGE 0.0V
J 0
(-4695 757);
DISPLAY 0.340426 (-4695 757);
PAINT SKYBLUE (-4695 757);
DISPLAY INVISIBLE (-4695 757);
FORCEADD ICS9FGP204..1
(-5500 1850);
FORCEPROP 2 LASTPIN (-6150 1250) $PN 20
J 2
(-6160 1260);
DISPLAY 0.617021 (-6160 1260);
PAINT ORANGE (-6160 1260);
FORCEPROP 2 LASTPIN (-6150 1400) $PN 6
J 2
(-6160 1410);
DISPLAY 0.617021 (-6160 1410);
PAINT ORANGE (-6160 1410);
FORCEPROP 1 LAST PART_NUMBER E95226-001
J 0
(-6100 900);
DISPLAY 0.617021 (-6100 900);
PAINT BLUE (-6100 900);
FORCEPROP 2 LASTPIN (-6150 1100) $PN 40
J 2
(-6160 1110);
DISPLAY 0.617021 (-6160 1110);
PAINT ORANGE (-6160 1110);
FORCEPROP 2 LASTPIN (-6150 1200) $PN 19
J 2
(-6160 1210);
DISPLAY 0.617021 (-6160 1210);
PAINT ORANGE (-6160 1210);
FORCEPROP 2 LASTPIN (-4850 2350) $PN 24
J 0
(-4840 2360);
DISPLAY 0.617021 (-4840 2360);
PAINT ORANGE (-4840 2360);
FORCEPROP 2 LASTPIN (-6150 1600) $PN 22
J 2
(-6160 1610);
DISPLAY 0.617021 (-6160 1610);
PAINT ORANGE (-6160 1610);
FORCEPROP 2 LASTPIN (-4850 2000) $PN 36
J 0
(-4840 2010);
DISPLAY 0.617021 (-4840 2010);
PAINT ORANGE (-4840 2010);
FORCEPROP 2 LASTPIN (-4850 1700) $PN 8
J 0
(-4840 1710);
DISPLAY 0.617021 (-4840 1710);
PAINT ORANGE (-4840 1710);
FORCEPROP 2 LASTPIN (-4850 2100) $PN 33
J 0
(-4840 2110);
DISPLAY 0.617021 (-4840 2110);
PAINT ORANGE (-4840 2110);
FORCEPROP 2 LASTPIN (-4850 2150) $PN 32
J 0
(-4840 2160);
DISPLAY 0.617021 (-4840 2160);
PAINT ORANGE (-4840 2160);
FORCEPROP 2 LASTPIN (-4850 2200) $PN 29
J 0
(-4840 2210);
DISPLAY 0.617021 (-4840 2210);
PAINT ORANGE (-4840 2210);
FORCEPROP 2 LASTPIN (-4850 2250) $PN 28
J 0
(-4840 2260);
DISPLAY 0.617021 (-4840 2260);
PAINT ORANGE (-4840 2260);
FORCEPROP 1 LAST LOCATION EU8F2
J 0
(-6100 2850);
DISPLAY 0.617021 (-6100 2850);
PAINT AQUA (-6100 2850);
FORCEPROP 2 LASTPIN (-4850 1950) $PN 37
J 0
(-4840 1960);
DISPLAY 0.617021 (-4840 1960);
PAINT ORANGE (-4840 1960);
FORCEPROP 2 LASTPIN (-4850 1050) $PN 14
J 0
(-4840 1060);
DISPLAY 0.617021 (-4840 1060);
PAINT ORANGE (-4840 1060);
FORCEPROP 2 LASTPIN (-4850 1100) $PN 18
J 0
(-4840 1110);
DISPLAY 0.617021 (-4840 1110);
PAINT ORANGE (-4840 1110);
FORCEPROP 2 LASTPIN (-4850 1850) $PN 4
J 0
(-4840 1860);
DISPLAY 0.617021 (-4840 1860);
PAINT ORANGE (-4840 1860);
FORCEPROP 1 LAST MATERIAL IC
J 0
(-6100 2800);
DISPLAY 0.617021 (-6100 2800);
PAINT SKYBLUE (-6100 2800);
FORCEPROP 2 LASTPIN (-6150 2450) $PN 31
J 2
(-6160 2460);
DISPLAY 0.617021 (-6160 2460);
PAINT ORANGE (-6160 2460);
FORCEPROP 2 LASTPIN (-6150 2150) $PN 15
J 2
(-6160 2160);
DISPLAY 0.617021 (-6160 2160);
PAINT ORANGE (-6160 2160);
FORCEPROP 2 LASTPIN (-6150 2050) $PN 9
J 2
(-6160 2060);
DISPLAY 0.617021 (-6160 2060);
PAINT ORANGE (-6160 2060);
FORCEPROP 2 LASTPIN (-6150 2300) $PN 2
J 2
(-6160 2310);
DISPLAY 0.617021 (-6160 2310);
PAINT ORANGE (-6160 2310);
FORCEPROP 2 LASTPIN (-6150 2250) $PN 23
J 2
(-6160 2260);
DISPLAY 0.617021 (-6160 2260);
PAINT ORANGE (-6160 2260);
FORCEPROP 2 LASTPIN (-6150 1900) $PN 39
J 2
(-6160 1910);
DISPLAY 0.617021 (-6160 1910);
PAINT ORANGE (-6160 1910);
FORCEPROP 2 LASTPIN (-6150 1950) $PN 38
J 2
(-6160 1960);
DISPLAY 0.617021 (-6160 1960);
PAINT ORANGE (-6160 1960);
FORCEPROP 2 LASTPIN (-4850 2300) $PN 25
J 0
(-4840 2310);
DISPLAY 0.617021 (-4840 2310);
PAINT ORANGE (-4840 2310);
FORCEPROP 2 LASTPIN (-4850 2650) $PN 11
J 0
(-4840 2660);
DISPLAY 0.617021 (-4840 2660);
PAINT ORANGE (-4840 2660);
FORCEPROP 2 LASTPIN (-4850 1450) $PN 30
J 0
(-4840 1460);
DISPLAY 0.617021 (-4840 1460);
PAINT ORANGE (-4840 1460);
FORCEPROP 2 LASTPIN (-4850 1000) $PN 10
J 0
(-4840 1010);
DISPLAY 0.617021 (-4840 1010);
PAINT ORANGE (-4840 1010);
FORCEPROP 2 LASTPIN (-4850 1550) $PN 35
J 0
(-4840 1560);
DISPLAY 0.617021 (-4840 1560);
PAINT ORANGE (-4840 1560);
FORCEPROP 2 LASTPIN (-4850 1200) $PN 21
J 0
(-4840 1210);
DISPLAY 0.617021 (-4840 1210);
PAINT ORANGE (-4840 1210);
FORCEPROP 2 LASTPIN (-4850 1300) $PN 41
J 0
(-4840 1310);
DISPLAY 0.617021 (-4840 1310);
PAINT ORANGE (-4840 1310);
FORCEPROP 2 LASTPIN (-4850 1250) $PN 1
J 0
(-4840 1260);
DISPLAY 0.617021 (-4840 1260);
PAINT ORANGE (-4840 1260);
FORCEPROP 2 LASTPIN (-4850 1800) $PN 3
J 0
(-4840 1810);
DISPLAY 0.617021 (-4840 1810);
PAINT ORANGE (-4840 1810);
FORCEPROP 2 LASTPIN (-4850 1650) $PN 7
J 0
(-4840 1660);
DISPLAY 0.617021 (-4840 1660);
PAINT ORANGE (-4840 1660);
FORCEPROP 2 LASTPIN (-4850 2600) $PN 13
J 0
(-4840 2610);
DISPLAY 0.617021 (-4840 2610);
PAINT ORANGE (-4840 2610);
FORCEPROP 2 LASTPIN (-4850 2450) $PN 16
J 0
(-4840 2460);
DISPLAY 0.617021 (-4840 2460);
PAINT ORANGE (-4840 2460);
FORCEPROP 2 LASTPIN (-6150 2100) $PN 12
J 2
(-6160 2110);
DISPLAY 0.617021 (-6160 2110);
PAINT ORANGE (-6160 2110);
FORCEPROP 2 LASTPIN (-6150 1450) $PN 5
J 2
(-6160 1460);
DISPLAY 0.617021 (-6160 1460);
PAINT ORANGE (-6160 1460);
FORCEPROP 2 LASTPIN (-4850 1400) $PN 27
J 0
(-4840 1410);
DISPLAY 0.617021 (-4840 1410);
PAINT ORANGE (-4840 1410);
FORCEPROP 2 LASTPIN (-4850 2500) $PN 17
J 0
(-4840 2510);
DISPLAY 0.617021 (-4840 2510);
PAINT ORANGE (-4840 2510);
FORCEPROP 2 LASTPIN (-6150 2550) $PN 34
J 2
(-6160 2560);
DISPLAY 0.617021 (-6160 2560);
PAINT ORANGE (-6160 2560);
FORCEPROP 2 LASTPIN (-6150 2400) $PN 26
J 2
(-6160 2410);
DISPLAY 0.617021 (-6160 2410);
PAINT ORANGE (-6160 2410);
FORCEPROP 1 LAST PACK_TYPE MLFP
J 0
(-6100 2900);
DISPLAY 1.617021 (-6100 2900);
PAINT SKYBLUE (-6100 2900);
DISPLAY INVISIBLE (-6100 2900);
FORCEPROP 2 LAST BOM_COST SM_CONTROLLER
J 0
(-6100 2900);
DISPLAY 1.617021 (-6100 2900);
PAINT WHITE (-6100 2900);
DISPLAY INVISIBLE (-6100 2900);
FORCEPROP 2 LAST CDS_LIB mstr_clock
J 0
(-5500 1850);
DISPLAY 1.617021 (-5500 1850);
PAINT MONO (-5500 1850);
DISPLAY INVISIBLE (-5500 1850);
FORCEPROP 1 LAST CDS_LMAN_SYM_OUTLINE -600,900,600,-900
J 0
(-5500 1850);
PAINT GREEN (-5500 1850);
DISPLAY INVISIBLE (-5500 1850);
FORCEPROP 2 LAST SEC_TYPE MLFP
J 0
(-6100 2900);
DISPLAY 1.021277 (-6100 2900);
PAINT ORANGE (-6100 2900);
DISPLAY INVISIBLE (-6100 2900);
FORCEPROP 2 LAST SEC 1
J 0
(-6100 2900);
DISPLAY 0.680851 (-6100 2900);
PAINT MONO (-6100 2900);
DISPLAY INVISIBLE (-6100 2900);
FORCEPROP 2 LAST CDS_LOCATION EU8F2
J 0
(-6100 2850);
DISPLAY 0.617021 (-6100 2850);
PAINT AQUA (-6100 2850);
DISPLAY INVISIBLE (-6100 2850);
FORCEPROP 1 LAST PATH I34
J 0
(-5500 2800);
PAINT GREEN (-5500 2800);
DISPLAY INVISIBLE (-5500 2800);
FORCEPROP 2 LAST ROOM SYS_CLOCK
J 0
(-6100 2900);
DISPLAY 2.276596 (-6100 2900);
PAINT WHITE (-6100 2900);
DISPLAY INVISIBLE (-6100 2900);
FORCEADD RES..2
(-7925 1225);
FORCEPROP 1 LAST PART_NUMBER G21796-026
J 0
(-7885 1100);
DISPLAY 0.617021 (-7885 1100);
PAINT BLUE (-7885 1100);
FORCEPROP 1 LAST VALUE 1.00K
J 0
(-7880 1300);
DISPLAY 0.617021 (-7880 1300);
PAINT SKYBLUE (-7880 1300);
FORCEPROP 1 LAST PACK_TYPE 0402
J 0
(-7885 1050);
DISPLAY 0.617021 (-7885 1050);
PAINT SKYBLUE (-7885 1050);
FORCEPROP 1 LASTPIN (-7925 1125) $PN 2
J 0
(-7920 1135);
DISPLAY 0.617021 (-7920 1135);
PAINT ORANGE (-7920 1135);
FORCEPROP 1 LAST WATTAGE 1/16W
J 0
(-7885 1200);
DISPLAY 0.617021 (-7885 1200);
PAINT SKYBLUE (-7885 1200);
FORCEPROP 1 LAST LOCATION R2T25
J 0
(-7880 1350);
DISPLAY 0.617021 (-7880 1350);
PAINT AQUA (-7880 1350);
FORCEPROP 1 LAST MATERIAL CHIP
J 0
(-7885 1150);
DISPLAY 0.617021 (-7885 1150);
PAINT SKYBLUE (-7885 1150);
FORCEPROP 1 LAST TOLERANCE 1%
J 0
(-7880 1250);
DISPLAY 0.617021 (-7880 1250);
PAINT SKYBLUE (-7880 1250);
FORCEPROP 1 LASTPIN (-7925 1325) $PN 1
J 0
(-7920 1287);
DISPLAY 0.617021 (-7920 1287);
PAINT ORANGE (-7920 1287);
FORCEPROP 1 LAST PATH I48
J 0
(-7875 1400);
DISPLAY 0.978723 (-7875 1400);
PAINT WHITE (-7875 1400);
DISPLAY INVISIBLE (-7875 1400);
FORCEPROP 2 LAST CDS_LIB mstr_discrete
J 2
(-7925 1225);
DISPLAY 1.617021 (-7925 1225);
PAINT MONO (-7925 1225);
DISPLAY INVISIBLE (-7925 1225);
FORCEPROP 2 LAST BOM_COST SM_CONTROLLER
J 2
(-7900 1375);
DISPLAY 1.617021 (-7900 1375);
PAINT WHITE (-7900 1375);
DISPLAY INVISIBLE (-7900 1375);
FORCEPROP 2 LAST SEC_TYPE 0402
J 0
(-7875 1450);
DISPLAY 1.021277 (-7875 1450);
PAINT ORANGE (-7875 1450);
DISPLAY INVISIBLE (-7875 1450);
FORCEPROP 2 LAST SEC 1
J 0
(-7875 1450);
DISPLAY 0.680851 (-7875 1450);
PAINT MONO (-7875 1450);
DISPLAY INVISIBLE (-7875 1450);
FORCEPROP 2 LAST CDS_LOCATION R2T25
J 0
(-7880 1350);
DISPLAY 0.617021 (-7880 1350);
PAINT AQUA (-7880 1350);
DISPLAY INVISIBLE (-7880 1350);
FORCEPROP 2 LAST ROOM SYS_CLOCK
J 2
(-7900 1400);
DISPLAY 1.127660 (-7900 1400);
PAINT WHITE (-7900 1400);
DISPLAY INVISIBLE (-7900 1400);
FORCEADD CRYSTAL..3
R 2
(-7350 1050);
FORCEPROP 1 LAST PART_NUMBER D71700-033
J 0
(-7450 1175);
DISPLAY 0.617021 (-7450 1175);
PAINT BLUE (-7450 1175);
FORCEPROP 1 LAST VALUE 25.000MHZ
J 0
(-7557 1111);
DISPLAY 0.617021 (-7557 1111);
PAINT SKYBLUE (-7557 1111);
FORCEPROP 1 LASTPIN (-7250 1050) $PN 1
J 0
(-7295 1060);
DISPLAY 0.617021 (-7295 1060);
PAINT WHITE (-7295 1060);
FORCEPROP 1 LASTPIN (-7450 1050) $PN 3
J 2
(-7415 1060);
DISPLAY 0.617021 (-7415 1060);
PAINT WHITE (-7415 1060);
FORCEPROP 1 LAST LOCATION Y8F1
J 0
(-7555 1174);
DISPLAY 0.617021 (-7555 1174);
PAINT AQUA (-7555 1174);
FORCEPROP 1 LAST MATERIAL IC
J 0
(-7289 1116);
DISPLAY 0.617021 (-7289 1116);
PAINT SKYBLUE (-7289 1116);
FORCEPROP 1 LAST POWER_GROUP GND=GND
J 0
(-7550 975);
DISPLAY 0.617021 (-7550 975);
PAINT ORANGE (-7550 975);
FORCEPROP 1 LAST PACK_TYPE 2013LF
J 2
(-7338 958);
DISPLAY 1.617021 (-7338 958);
PAINT SKYBLUE (-7338 958);
DISPLAY INVISIBLE (-7338 958);
FORCEPROP 0 LAST BOM_COST SM_CONTROLLER
J 0
(-7250 1300);
DISPLAY 1.021277 (-7250 1300);
PAINT ORANGE (-7250 1300);
DISPLAY INVISIBLE (-7250 1300);
FORCEPROP 2 LAST CDS_LIB mstr_discrete
J 2
(-7350 1050);
DISPLAY 1.617021 (-7350 1050);
PAINT ORANGE (-7350 1050);
DISPLAY INVISIBLE (-7350 1050);
FORCEPROP 2 LAST CDS_SEC 1
J 2
(-7375 1200);
DISPLAY 2.276596 (-7375 1200);
PAINT ORANGE (-7375 1200);
DISPLAY INVISIBLE (-7375 1200);
FORCEPROP 2 LAST $SEC 1
J 2
(-7375 1200);
DISPLAY 1.510638 (-7375 1200);
PAINT MONO (-7375 1200);
DISPLAY INVISIBLE (-7375 1200);
FORCEPROP 2 LAST CDS_LOCATION Y8F1
J 1
(-7355 1149);
DISPLAY 0.617021 (-7355 1149);
PAINT AQUA (-7355 1149);
DISPLAY INVISIBLE (-7355 1149);
FORCEPROP 1 LAST PATH I52
J 2
(-7375 1150);
DISPLAY 0.872340 (-7375 1150);
PAINT PINK (-7375 1150);
DISPLAY INVISIBLE (-7375 1150);
FORCEPROP 2 LAST ROOM SYS_CLOCK
J 2
(-7375 1250);
DISPLAY 2.276596 (-7375 1250);
PAINT WHITE (-7375 1250);
DISPLAY INVISIBLE (-7375 1250);
FORCEADD GND..1
(-7350 400);
FORCEPROP 3 LASTPIN (-7350 450) SIG_NAME GND\g
J 0
(-7340 460);
DISPLAY 0.659574 (-7340 460);
PAINT MONO (-7340 460);
DISPLAY INVISIBLE (-7340 460);
FORCEPROP 1 LAST HDL_POWER GND
J 0
(-7350 550);
PAINT GREEN (-7350 550);
DISPLAY INVISIBLE (-7350 550);
FORCEPROP 1 LAST BODY_TYPE PLUMBING
J 0
(-7395 357);
DISPLAY 0.340426 (-7395 357);
PAINT GREEN (-7395 357);
DISPLAY INVISIBLE (-7395 357);
FORCEPROP 1 LAST VOLTAGE 0.0V
J 0
(-7395 357);
DISPLAY 0.340426 (-7395 357);
PAINT SKYBLUE (-7395 357);
DISPLAY INVISIBLE (-7395 357);
FORCEPROP 2 LAST CDS_LIB mstr_symbols
J 0
(-7350 400);
DISPLAY 1.617021 (-7350 400);
PAINT MONO (-7350 400);
DISPLAY INVISIBLE (-7350 400);
FORCEPROP 1 LAST SIZE 1B
J 0
(-7275 350);
DISPLAY 1.127660 (-7275 350);
PAINT ORANGE (-7275 350);
DISPLAY INVISIBLE (-7275 350);
FORCEPROP 2 LAST BOM_COST SM_CONTROLLER
J 0
(-7800 475);
DISPLAY 1.617021 (-7800 475);
PAINT WHITE (-7800 475);
DISPLAY INVISIBLE (-7800 475);
FORCEPROP 1 LAST PATH I54
J 0
(-7275 400);
DISPLAY 0.872340 (-7275 400);
PAINT AQUA (-7275 400);
DISPLAY INVISIBLE (-7275 400);
FORCEPROP 2 LAST ROOM SYS_CLOCK
J 0
(-7675 475);
DISPLAY 1.127660 (-7675 475);
PAINT WHITE (-7675 475);
DISPLAY INVISIBLE (-7675 475);
FORCEADD OFFPAGE..1
(-7400 150);
FORCEPROP 2 LAST $XR5 239 
J 0
(-8252 150);
DISPLAY 0.638298 (-8252 150);
PAINT MONO (-8252 150);
FORCEPROP 2 LAST $XR4 237 
J 0
(-8132 150);
DISPLAY 0.638298 (-8132 150);
PAINT MONO (-8132 150);
FORCEPROP 2 LAST $XR3 196 
J 0
(-8012 150);
DISPLAY 0.638298 (-8012 150);
PAINT MONO (-8012 150);
FORCEPROP 2 LAST $XR2 191 
J 0
(-7892 150);
DISPLAY 0.638298 (-7892 150);
PAINT MONO (-7892 150);
FORCEPROP 2 LAST $XR1 189 
J 0
(-7772 150);
DISPLAY 0.638298 (-7772 150);
PAINT MONO (-7772 150);
FORCEPROP 2 LAST $XR0 240 
J 0
(-7652 150);
DISPLAY 0.638298 (-7652 150);
PAINT MONO (-7652 150);
FORCEPROP 1 LAST COMMENT_BODY TRUE
J 0
(-7275 50);
DISPLAY 1.404255 (-7275 50);
PAINT PEACH (-7275 50);
DISPLAY INVISIBLE (-7275 50);
FORCEPROP 1 LAST OFFPAGE TRUE
J 0
(-7075 25);
PAINT GREEN (-7075 25);
DISPLAY INVISIBLE (-7075 25);
FORCEPROP 2 LAST PATH I55
J 0
(-7650 200);
DISPLAY 1.021277 (-7650 200);
PAINT ORANGE (-7650 200);
DISPLAY INVISIBLE (-7650 200);
FORCEPROP 2 LAST CDS_LIB mstr_standard
J 0
(-7400 150);
DISPLAY 1.617021 (-7400 150);
PAINT MONO (-7400 150);
DISPLAY INVISIBLE (-7400 150);
FORCEADD GND..1
(-8475 3650);
FORCEPROP 3 LASTPIN (-8475 3700) SIG_NAME GND\g
J 0
(-8465 3710);
DISPLAY 0.659574 (-8465 3710);
PAINT MONO (-8465 3710);
DISPLAY INVISIBLE (-8465 3710);
FORCEPROP 1 LAST HDL_POWER GND
J 0
(-8475 3800);
PAINT GREEN (-8475 3800);
DISPLAY INVISIBLE (-8475 3800);
FORCEPROP 1 LAST BODY_TYPE PLUMBING
J 0
(-8520 3607);
DISPLAY 0.340426 (-8520 3607);
PAINT GREEN (-8520 3607);
DISPLAY INVISIBLE (-8520 3607);
FORCEPROP 2 LAST ROOM SYS_CLOCK
J 0
(-8800 3725);
DISPLAY 1.127660 (-8800 3725);
PAINT WHITE (-8800 3725);
DISPLAY INVISIBLE (-8800 3725);
FORCEPROP 1 LAST PATH I58
J 0
(-8400 3650);
DISPLAY 0.872340 (-8400 3650);
PAINT AQUA (-8400 3650);
DISPLAY INVISIBLE (-8400 3650);
FORCEPROP 1 LAST SIZE 1B
J 0
(-8400 3600);
DISPLAY 1.127660 (-8400 3600);
PAINT GREEN (-8400 3600);
DISPLAY INVISIBLE (-8400 3600);
FORCEPROP 2 LAST CDS_LIB mstr_symbols
J 0
(-8475 3650);
DISPLAY 2.127660 (-8475 3650);
PAINT ORANGE (-8475 3650);
DISPLAY INVISIBLE (-8475 3650);
FORCEPROP 2 LAST BOM_COST SM_CONTROLLER
J 0
(-8925 3725);
DISPLAY 1.617021 (-8925 3725);
PAINT WHITE (-8925 3725);
DISPLAY INVISIBLE (-8925 3725);
FORCEPROP 1 LAST VOLTAGE 0.0V
J 0
(-8520 3607);
DISPLAY 0.340426 (-8520 3607);
PAINT SKYBLUE (-8520 3607);
DISPLAY INVISIBLE (-8520 3607);
FORCEADD GND..1
(-7925 900);
FORCEPROP 3 LASTPIN (-7925 950) SIG_NAME GND\g
J 0
(-7915 960);
DISPLAY 0.659574 (-7915 960);
PAINT MONO (-7915 960);
DISPLAY INVISIBLE (-7915 960);
FORCEPROP 1 LAST HDL_POWER GND
J 0
(-7925 1050);
PAINT GREEN (-7925 1050);
DISPLAY INVISIBLE (-7925 1050);
FORCEPROP 1 LAST BODY_TYPE PLUMBING
J 0
(-7970 857);
DISPLAY 0.340426 (-7970 857);
PAINT GREEN (-7970 857);
DISPLAY INVISIBLE (-7970 857);
FORCEPROP 1 LAST PATH I64
J 0
(-7850 900);
DISPLAY 0.872340 (-7850 900);
PAINT AQUA (-7850 900);
DISPLAY INVISIBLE (-7850 900);
FORCEPROP 1 LAST VOLTAGE 0.0V
J 0
(-7970 857);
DISPLAY 0.340426 (-7970 857);
PAINT SKYBLUE (-7970 857);
DISPLAY INVISIBLE (-7970 857);
FORCEPROP 2 LAST CDS_LIB mstr_symbols
J 0
(-7925 900);
PAINT ORANGE (-7925 900);
DISPLAY INVISIBLE (-7925 900);
FORCEPROP 1 LAST SIZE 1B
J 0
(-7850 850);
DISPLAY 1.127660 (-7850 850);
PAINT ORANGE (-7850 850);
DISPLAY INVISIBLE (-7850 850);
FORCEPROP 2 LAST BOM_COST SM_CONTROLLER
J 0
(-8375 975);
DISPLAY 1.617021 (-8375 975);
PAINT WHITE (-8375 975);
DISPLAY INVISIBLE (-8375 975);
FORCEPROP 2 LAST ROOM SYS_CLOCK
J 0
(-8250 975);
DISPLAY 1.127660 (-8250 975);
PAINT WHITE (-8250 975);
DISPLAY INVISIBLE (-8250 975);
FORCEADD OFFPAGE..2
(-1875 1700);
FORCEPROP 2 LAST $XR0 147 
J 0
(-1686 1700);
DISPLAY 0.638298 (-1686 1700);
PAINT MONO (-1686 1700);
FORCEPROP 1 LAST COMMENT_BODY TRUE
J 0
(-1920 1605);
DISPLAY 0.872340 (-1920 1605);
PAINT GREEN (-1920 1605);
DISPLAY INVISIBLE (-1920 1605);
FORCEPROP 1 LAST OFFPAGE TRUE
J 0
(-1550 1575);
DISPLAY 0.872340 (-1550 1575);
PAINT GREEN (-1550 1575);
DISPLAY INVISIBLE (-1550 1575);
FORCEPROP 2 LAST PATH I71
J 0
(-1825 1775);
DISPLAY 1.021277 (-1825 1775);
PAINT ORANGE (-1825 1775);
DISPLAY INVISIBLE (-1825 1775);
FORCEPROP 2 LAST CDS_LIB mstr_standard
J 0
(-1875 1700);
PAINT ORANGE (-1875 1700);
DISPLAY INVISIBLE (-1875 1700);
FORCEADD OFFPAGE..2
(-1875 1550);
FORCEPROP 2 LAST $XR0 186 
J 0
(-1686 1550);
DISPLAY 0.638298 (-1686 1550);
PAINT MONO (-1686 1550);
FORCEPROP 1 LAST COMMENT_BODY TRUE
J 0
(-1920 1455);
DISPLAY 0.872340 (-1920 1455);
PAINT GREEN (-1920 1455);
DISPLAY INVISIBLE (-1920 1455);
FORCEPROP 1 LAST OFFPAGE TRUE
J 0
(-1550 1425);
DISPLAY 0.872340 (-1550 1425);
PAINT GREEN (-1550 1425);
DISPLAY INVISIBLE (-1550 1425);
FORCEPROP 2 LAST PATH I72
J 0
(-1700 1625);
DISPLAY 1.021277 (-1700 1625);
PAINT ORANGE (-1700 1625);
DISPLAY INVISIBLE (-1700 1625);
FORCEPROP 2 LAST CDS_LIB mstr_standard
J 0
(-1875 1550);
PAINT ORANGE (-1875 1550);
DISPLAY INVISIBLE (-1875 1550);
FORCEADD OFFPAGE..2
(-1875 2150);
FORCEPROP 2 LAST $XR0 121 
J 0
(-1686 2150);
DISPLAY 0.638298 (-1686 2150);
PAINT MONO (-1686 2150);
FORCEPROP 1 LAST COMMENT_BODY TRUE
J 0
(-1920 2055);
DISPLAY 1.404255 (-1920 2055);
PAINT PEACH (-1920 2055);
DISPLAY INVISIBLE (-1920 2055);
FORCEPROP 1 LAST OFFPAGE TRUE
J 0
(-1550 2025);
PAINT GREEN (-1550 2025);
DISPLAY INVISIBLE (-1550 2025);
FORCEPROP 2 LAST PATH I79
J 0
(-1675 2200);
DISPLAY 1.021277 (-1675 2200);
PAINT ORANGE (-1675 2200);
DISPLAY INVISIBLE (-1675 2200);
FORCEPROP 2 LAST CDS_LIB mstr_standard
J 0
(-1875 2150);
DISPLAY 1.617021 (-1875 2150);
PAINT MONO (-1875 2150);
DISPLAY INVISIBLE (-1875 2150);
FORCEADD OFFPAGE..2
(-1875 1850);
FORCEPROP 2 LAST $XR0 147 
J 0
(-1686 1850);
DISPLAY 0.638298 (-1686 1850);
PAINT MONO (-1686 1850);
FORCEPROP 1 LAST COMMENT_BODY TRUE
J 0
(-1920 1755);
DISPLAY 1.404255 (-1920 1755);
PAINT PEACH (-1920 1755);
DISPLAY INVISIBLE (-1920 1755);
FORCEPROP 1 LAST OFFPAGE TRUE
J 0
(-1550 1725);
PAINT GREEN (-1550 1725);
DISPLAY INVISIBLE (-1550 1725);
FORCEPROP 2 LAST PATH I80
J 0
(-1700 1925);
DISPLAY 1.021277 (-1700 1925);
PAINT ORANGE (-1700 1925);
DISPLAY INVISIBLE (-1700 1925);
FORCEPROP 2 LAST CDS_LIB mstr_standard
J 0
(-1875 1850);
DISPLAY 1.617021 (-1875 1850);
PAINT MONO (-1875 1850);
DISPLAY INVISIBLE (-1875 1850);
FORCEADD OFFPAGE..2
(-1875 2000);
FORCEPROP 2 LAST $XR0 139 
J 0
(-1686 2000);
DISPLAY 0.638298 (-1686 2000);
PAINT MONO (-1686 2000);
FORCEPROP 1 LAST COMMENT_BODY TRUE
J 0
(-1920 1905);
DISPLAY 1.404255 (-1920 1905);
PAINT PEACH (-1920 1905);
DISPLAY INVISIBLE (-1920 1905);
FORCEPROP 1 LAST OFFPAGE TRUE
J 0
(-1550 1875);
PAINT GREEN (-1550 1875);
DISPLAY INVISIBLE (-1550 1875);
FORCEPROP 2 LAST PATH I81
J 0
(-1675 2050);
DISPLAY 1.021277 (-1675 2050);
PAINT ORANGE (-1675 2050);
DISPLAY INVISIBLE (-1675 2050);
FORCEPROP 2 LAST CDS_LIB mstr_standard
J 0
(-1875 2000);
PAINT ORANGE (-1875 2000);
DISPLAY INVISIBLE (-1875 2000);
FORCEADD OFFPAGE..2
(-1875 2600);
FORCEPROP 2 LASTPIN (-1925 2600) SIG_NAME CLK_25M_CPLD
J 0
(-2550 2610);
DISPLAY 0.617021 (-2550 2610);
PAINT ORANGE (-2550 2610);
FORCEPROP 2 LAST $XR0 190 
J 0
(-1686 2600);
DISPLAY 0.638298 (-1686 2600);
PAINT MONO (-1686 2600);
FORCEPROP 1 LAST COMMENT_BODY TRUE
J 0
(-1920 2505);
DISPLAY 1.404255 (-1920 2505);
PAINT PEACH (-1920 2505);
DISPLAY INVISIBLE (-1920 2505);
FORCEPROP 1 LAST OFFPAGE TRUE
J 0
(-1550 2475);
PAINT GREEN (-1550 2475);
DISPLAY INVISIBLE (-1550 2475);
FORCEPROP 2 LAST PATH I87
J 0
(-1700 2675);
DISPLAY 1.021277 (-1700 2675);
PAINT ORANGE (-1700 2675);
DISPLAY INVISIBLE (-1700 2675);
FORCEPROP 2 LAST CDS_LIB mstr_standard
J 0
(-1875 2600);
PAINT ORANGE (-1875 2600);
DISPLAY INVISIBLE (-1875 2600);
FORCEADD CAP_A..1
(-3625 3925);
FORCEPROP 1 LAST MATERIAL X6S
J 0
(-3575 3825);
DISPLAY 0.617021 (-3575 3825);
PAINT SKYBLUE (-3575 3825);
FORCEPROP 1 LASTPIN (-3625 3825) $PN 2
J 0
(-3615 3805);
DISPLAY 0.617021 (-3615 3805);
PAINT WHITE (-3615 3805);
FORCEPROP 1 LAST PACK_TYPE 0402V
J 0
(-3575 3725);
DISPLAY 0.617021 (-3575 3725);
PAINT SKYBLUE (-3575 3725);
FORCEPROP 1 LAST PART_NUMBER D97712-004
J 0
(-3575 3775);
DISPLAY 0.617021 (-3575 3775);
PAINT BLUE (-3575 3775);
FORCEPROP 1 LAST LOCATION C2T31
J 0
(-3575 4025);
DISPLAY 0.617021 (-3575 4025);
PAINT AQUA (-3575 4025);
FORCEPROP 1 LAST VALUE 1.0UF
J 0
(-3575 3975);
DISPLAY 0.617021 (-3575 3975);
PAINT SKYBLUE (-3575 3975);
FORCEPROP 1 LAST VOLTAGE 6.3V
J 0
(-3575 3925);
DISPLAY 0.617021 (-3575 3925);
PAINT SKYBLUE (-3575 3925);
FORCEPROP 1 LASTPIN (-3625 4025) $PN 1
J 0
(-3615 4005);
DISPLAY 0.617021 (-3615 4005);
PAINT WHITE (-3615 4005);
FORCEPROP 1 LAST TOLERANCE 10%
J 0
(-3575 3875);
DISPLAY 0.617021 (-3575 3875);
PAINT SKYBLUE (-3575 3875);
FORCEPROP 2 LAST CDS_LOCATION C2T31
J 0
(-3575 4025);
DISPLAY 0.617021 (-3575 4025);
PAINT AQUA (-3575 4025);
DISPLAY INVISIBLE (-3575 4025);
FORCEPROP 2 LAST BOM_COST SM_CONTROLLER
J 0
(-3575 4050);
DISPLAY 1.617021 (-3575 4050);
PAINT WHITE (-3575 4050);
DISPLAY INVISIBLE (-3575 4050);
FORCEPROP 2 LAST CDS_LIB dev_discrete
J 0
(-3625 3925);
PAINT ORANGE (-3625 3925);
DISPLAY INVISIBLE (-3625 3925);
FORCEPROP 2 LAST CDS_SEC 1
J 0
(-3575 4125);
DISPLAY 2.276596 (-3575 4125);
PAINT ORANGE (-3575 4125);
DISPLAY INVISIBLE (-3575 4125);
FORCEPROP 2 LAST $SEC 1
J 0
(-3575 4125);
DISPLAY 1.510638 (-3575 4125);
PAINT MONO (-3575 4125);
DISPLAY INVISIBLE (-3575 4125);
FORCEPROP 1 LAST PATH I89
J 0
(-3575 4075);
DISPLAY 0.978723 (-3575 4075);
PAINT WHITE (-3575 4075);
DISPLAY INVISIBLE (-3575 4075);
FORCEPROP 2 LAST ROOM SYS_CLOCK
J 0
(-3575 4075);
DISPLAY 1.127660 (-3575 4075);
PAINT WHITE (-3575 4075);
DISPLAY INVISIBLE (-3575 4075);
FORCEADD CAP_A..1
(-4050 3925);
FORCEPROP 1 LAST PART_NUMBER A36096-045
J 0
(-4000 3775);
DISPLAY 0.617021 (-4000 3775);
PAINT BLUE (-4000 3775);
FORCEPROP 1 LAST PACK_TYPE 0402V
J 0
(-4000 3725);
DISPLAY 0.617021 (-4000 3725);
PAINT SKYBLUE (-4000 3725);
FORCEPROP 1 LAST LOCATION C2T27
J 0
(-4000 4025);
DISPLAY 0.617021 (-4000 4025);
PAINT AQUA (-4000 4025);
FORCEPROP 1 LAST VALUE 0.01UF
J 0
(-4000 3975);
DISPLAY 0.617021 (-4000 3975);
PAINT SKYBLUE (-4000 3975);
FORCEPROP 1 LAST TOLERANCE 10%
J 0
(-4000 3875);
DISPLAY 0.617021 (-4000 3875);
PAINT SKYBLUE (-4000 3875);
FORCEPROP 1 LAST VOLTAGE 25V
J 0
(-4000 3925);
DISPLAY 0.617021 (-4000 3925);
PAINT SKYBLUE (-4000 3925);
FORCEPROP 1 LAST MATERIAL X7R
J 0
(-4000 3825);
DISPLAY 0.617021 (-4000 3825);
PAINT SKYBLUE (-4000 3825);
FORCEPROP 1 LASTPIN (-4050 4025) $PN 1
J 0
(-4040 4005);
DISPLAY 0.617021 (-4040 4005);
PAINT WHITE (-4040 4005);
FORCEPROP 1 LASTPIN (-4050 3825) $PN 2
J 0
(-4040 3805);
DISPLAY 0.617021 (-4040 3805);
PAINT WHITE (-4040 3805);
FORCEPROP 2 LAST CDS_LOCATION C2T27
J 0
(-4000 4025);
DISPLAY 0.617021 (-4000 4025);
PAINT AQUA (-4000 4025);
DISPLAY INVISIBLE (-4000 4025);
FORCEPROP 2 LAST BOM_COST SM_CONTROLLER
J 0
(-4000 4050);
DISPLAY 1.617021 (-4000 4050);
PAINT WHITE (-4000 4050);
DISPLAY INVISIBLE (-4000 4050);
FORCEPROP 2 LAST CDS_LIB dev_discrete
J 0
(-4050 3925);
PAINT ORANGE (-4050 3925);
DISPLAY INVISIBLE (-4050 3925);
FORCEPROP 2 LAST CDS_SEC 1
J 0
(-4000 4125);
DISPLAY 2.276596 (-4000 4125);
PAINT ORANGE (-4000 4125);
DISPLAY INVISIBLE (-4000 4125);
FORCEPROP 2 LAST $SEC 1
J 0
(-4000 4125);
DISPLAY 1.510638 (-4000 4125);
PAINT MONO (-4000 4125);
DISPLAY INVISIBLE (-4000 4125);
FORCEPROP 1 LAST PATH I90
J 0
(-4000 4075);
DISPLAY 0.978723 (-4000 4075);
PAINT WHITE (-4000 4075);
DISPLAY INVISIBLE (-4000 4075);
FORCEPROP 2 LAST ROOM SYS_CLOCK
J 0
(-4000 4075);
DISPLAY 1.127660 (-4000 4075);
PAINT WHITE (-4000 4075);
DISPLAY INVISIBLE (-4000 4075);
FORCEADD RES..1
(-4325 4150);
FORCEPROP 1 LAST LOCATION R2T23
J 0
(-4375 4200);
DISPLAY 0.617021 (-4375 4200);
PAINT AQUA (-4375 4200);
FORCEPROP 1 LAST PART_NUMBER G22026-127
J 0
(-4450 4100);
DISPLAY 0.617021 (-4450 4100);
PAINT BLUE (-4450 4100);
FORCEPROP 1 LAST VALUE 2.2
J 2
(-4350 4050);
DISPLAY 0.617021 (-4350 4050);
PAINT SKYBLUE (-4350 4050);
FORCEPROP 1 LAST TOLERANCE 1.0%
J 0
(-4325 4050);
DISPLAY 0.617021 (-4325 4050);
PAINT SKYBLUE (-4325 4050);
FORCEPROP 1 LAST PACK_TYPE 0603
J 0
(-4425 3950);
DISPLAY 0.617021 (-4425 3950);
PAINT SKYBLUE (-4425 3950);
FORCEPROP 1 LAST MATERIAL CHIP
J 0
(-4325 4000);
DISPLAY 0.617021 (-4325 4000);
PAINT SKYBLUE (-4325 4000);
FORCEPROP 1 LAST WATTAGE 1/10W
J 2
(-4350 4000);
DISPLAY 0.617021 (-4350 4000);
PAINT SKYBLUE (-4350 4000);
FORCEPROP 1 LASTPIN (-4225 4150) $PN 2
J 0
(-4263 4162);
DISPLAY 0.617021 (-4263 4162);
PAINT WHITE (-4263 4162);
FORCEPROP 1 LASTPIN (-4425 4150) $PN 1
J 0
(-4413 4162);
DISPLAY 0.617021 (-4413 4162);
PAINT WHITE (-4413 4162);
FORCEPROP 2 LAST CDS_LIB mstr_discrete
J 0
(-4325 4150);
DISPLAY 1.617021 (-4325 4150);
PAINT MONO (-4325 4150);
DISPLAY INVISIBLE (-4325 4150);
FORCEPROP 2 LAST BOM_COST SM_CONTROLLER
J 0
(-4375 4225);
DISPLAY 1.617021 (-4375 4225);
PAINT WHITE (-4375 4225);
DISPLAY INVISIBLE (-4375 4225);
FORCEPROP 2 LAST CDS_SEC 1
J 0
(-4375 4350);
DISPLAY 2.276596 (-4375 4350);
PAINT ORANGE (-4375 4350);
DISPLAY INVISIBLE (-4375 4350);
FORCEPROP 2 LAST $SEC 1
J 0
(-4375 4350);
DISPLAY 1.510638 (-4375 4350);
PAINT MONO (-4375 4350);
DISPLAY INVISIBLE (-4375 4350);
FORCEPROP 2 LAST CDS_LOCATION R2T23
J 0
(-4375 4200);
DISPLAY 0.617021 (-4375 4200);
PAINT AQUA (-4375 4200);
DISPLAY INVISIBLE (-4375 4200);
FORCEPROP 1 LAST PATH I94
J 0
(-4375 4300);
DISPLAY 0.978723 (-4375 4300);
PAINT WHITE (-4375 4300);
DISPLAY INVISIBLE (-4375 4300);
FORCEPROP 2 LAST ROOM SYS_CLOCK
J 0
(-4375 4300);
DISPLAY 1.127660 (-4375 4300);
PAINT WHITE (-4375 4300);
DISPLAY INVISIBLE (-4375 4300);
FORCEADD RES..1
(-2825 4200);
FORCEPROP 1 LAST PACK_TYPE 0603
J 0
(-2925 4000);
DISPLAY 0.617021 (-2925 4000);
PAINT SKYBLUE (-2925 4000);
FORCEPROP 1 LAST MATERIAL CHIP
J 0
(-2825 4050);
DISPLAY 0.617021 (-2825 4050);
PAINT SKYBLUE (-2825 4050);
FORCEPROP 1 LAST TOLERANCE 1.0%
J 0
(-2825 4100);
DISPLAY 0.617021 (-2825 4100);
PAINT SKYBLUE (-2825 4100);
FORCEPROP 1 LAST PART_NUMBER G22026-127
J 0
(-2950 4150);
DISPLAY 0.617021 (-2950 4150);
PAINT BLUE (-2950 4150);
FORCEPROP 1 LAST VALUE 2.2
J 2
(-2850 4100);
DISPLAY 0.617021 (-2850 4100);
PAINT SKYBLUE (-2850 4100);
FORCEPROP 1 LASTPIN (-2925 4200) $PN 1
J 0
(-2913 4212);
DISPLAY 0.617021 (-2913 4212);
PAINT WHITE (-2913 4212);
FORCEPROP 1 LASTPIN (-2725 4200) $PN 2
J 0
(-2763 4212);
DISPLAY 0.617021 (-2763 4212);
PAINT WHITE (-2763 4212);
FORCEPROP 1 LAST WATTAGE 1/10W
J 2
(-2850 4050);
DISPLAY 0.617021 (-2850 4050);
PAINT SKYBLUE (-2850 4050);
FORCEPROP 1 LAST LOCATION R2T52
J 0
(-2875 4250);
DISPLAY 0.617021 (-2875 4250);
PAINT AQUA (-2875 4250);
FORCEPROP 2 LAST ROOM SYS_CLOCK
J 0
(-2875 4350);
DISPLAY 1.127660 (-2875 4350);
PAINT WHITE (-2875 4350);
DISPLAY INVISIBLE (-2875 4350);
FORCEPROP 1 LAST PATH I95
J 0
(-2875 4350);
DISPLAY 0.978723 (-2875 4350);
PAINT WHITE (-2875 4350);
DISPLAY INVISIBLE (-2875 4350);
FORCEPROP 2 LAST CDS_LOCATION R2T52
J 0
(-2875 4250);
DISPLAY 0.617021 (-2875 4250);
PAINT AQUA (-2875 4250);
DISPLAY INVISIBLE (-2875 4250);
FORCEPROP 2 LAST $SEC 1
J 0
(-2875 4450);
DISPLAY 1.510638 (-2875 4450);
PAINT MONO (-2875 4450);
DISPLAY INVISIBLE (-2875 4450);
FORCEPROP 2 LAST CDS_SEC 1
J 0
(-2875 4400);
DISPLAY 2.276596 (-2875 4400);
PAINT ORANGE (-2875 4400);
DISPLAY INVISIBLE (-2875 4400);
FORCEPROP 2 LAST CDS_LIB mstr_discrete
J 0
(-2825 4200);
DISPLAY 2.127660 (-2825 4200);
PAINT ORANGE (-2825 4200);
DISPLAY INVISIBLE (-2825 4200);
FORCEPROP 2 LAST BOM_COST SM_CONTROLLER
J 0
(-2875 4275);
DISPLAY 1.617021 (-2875 4275);
PAINT WHITE (-2875 4275);
DISPLAY INVISIBLE (-2875 4275);
FORCEADD GND..1
(-3625 3625);
FORCEPROP 3 LASTPIN (-3625 3675) SIG_NAME GND\g
J 0
(-3615 3685);
DISPLAY 0.659574 (-3615 3685);
PAINT MONO (-3615 3685);
DISPLAY INVISIBLE (-3615 3685);
FORCEPROP 1 LAST HDL_POWER GND
J 0
(-3625 3775);
PAINT GREEN (-3625 3775);
DISPLAY INVISIBLE (-3625 3775);
FORCEPROP 1 LAST BODY_TYPE PLUMBING
J 0
(-3670 3582);
DISPLAY 0.340426 (-3670 3582);
PAINT GREEN (-3670 3582);
DISPLAY INVISIBLE (-3670 3582);
FORCEPROP 1 LAST VOLTAGE 0.0V
J 0
(-3670 3582);
DISPLAY 0.340426 (-3670 3582);
PAINT SKYBLUE (-3670 3582);
DISPLAY INVISIBLE (-3670 3582);
FORCEPROP 1 LAST SIZE 1B
J 0
(-3550 3575);
DISPLAY 1.127660 (-3550 3575);
PAINT GREEN (-3550 3575);
DISPLAY INVISIBLE (-3550 3575);
FORCEPROP 2 LAST CDS_LIB mstr_symbols
J 0
(-3625 3625);
DISPLAY 1.617021 (-3625 3625);
PAINT MONO (-3625 3625);
DISPLAY INVISIBLE (-3625 3625);
FORCEPROP 2 LAST BOM_COST SM_CONTROLLER
J 0
(-4075 3700);
DISPLAY 1.617021 (-4075 3700);
PAINT WHITE (-4075 3700);
DISPLAY INVISIBLE (-4075 3700);
FORCEPROP 1 LAST PATH I96
J 0
(-3550 3625);
DISPLAY 0.872340 (-3550 3625);
PAINT AQUA (-3550 3625);
DISPLAY INVISIBLE (-3550 3625);
FORCEPROP 2 LAST ROOM SYS_CLOCK
J 0
(-3950 3700);
DISPLAY 1.127660 (-3950 3700);
PAINT WHITE (-3950 3700);
DISPLAY INVISIBLE (-3950 3700);
FORCEADD CAP_A..1
(-2250 4000);
FORCEPROP 1 LAST PART_NUMBER D97712-004
J 0
(-2200 3850);
DISPLAY 0.617021 (-2200 3850);
PAINT BLUE (-2200 3850);
FORCEPROP 1 LAST LOCATION C2T38
J 0
(-2200 4100);
DISPLAY 0.617021 (-2200 4100);
PAINT AQUA (-2200 4100);
FORCEPROP 1 LAST VALUE 1.0UF
J 0
(-2200 4050);
DISPLAY 0.617021 (-2200 4050);
PAINT SKYBLUE (-2200 4050);
FORCEPROP 1 LAST PACK_TYPE 0402V
J 0
(-2200 3800);
DISPLAY 0.617021 (-2200 3800);
PAINT SKYBLUE (-2200 3800);
FORCEPROP 1 LAST VOLTAGE 6.3V
J 0
(-2200 4000);
DISPLAY 0.617021 (-2200 4000);
PAINT SKYBLUE (-2200 4000);
FORCEPROP 1 LAST MATERIAL X6S
J 0
(-2200 3900);
DISPLAY 0.617021 (-2200 3900);
PAINT SKYBLUE (-2200 3900);
FORCEPROP 1 LAST TOLERANCE 10%
J 0
(-2200 3950);
DISPLAY 0.617021 (-2200 3950);
PAINT SKYBLUE (-2200 3950);
FORCEPROP 1 LASTPIN (-2250 3900) $PN 2
J 0
(-2240 3880);
DISPLAY 0.617021 (-2240 3880);
PAINT WHITE (-2240 3880);
FORCEPROP 1 LASTPIN (-2250 4100) $PN 1
J 0
(-2240 4080);
DISPLAY 0.617021 (-2240 4080);
PAINT WHITE (-2240 4080);
FORCEPROP 2 LAST ROOM SYS_CLOCK
J 0
(-2200 4150);
DISPLAY 1.127660 (-2200 4150);
PAINT WHITE (-2200 4150);
DISPLAY INVISIBLE (-2200 4150);
FORCEPROP 1 LAST PATH I97
J 0
(-2200 4150);
DISPLAY 0.978723 (-2200 4150);
PAINT WHITE (-2200 4150);
DISPLAY INVISIBLE (-2200 4150);
FORCEPROP 2 LAST $SEC 1
J 0
(-2200 4200);
DISPLAY 1.510638 (-2200 4200);
PAINT MONO (-2200 4200);
DISPLAY INVISIBLE (-2200 4200);
FORCEPROP 2 LAST CDS_SEC 1
J 0
(-2200 4200);
DISPLAY 2.276596 (-2200 4200);
PAINT ORANGE (-2200 4200);
DISPLAY INVISIBLE (-2200 4200);
FORCEPROP 2 LAST CDS_LIB dev_discrete
J 0
(-2250 4000);
PAINT ORANGE (-2250 4000);
DISPLAY INVISIBLE (-2250 4000);
FORCEPROP 2 LAST BOM_COST SM_CONTROLLER
J 0
(-2200 4125);
DISPLAY 1.617021 (-2200 4125);
PAINT WHITE (-2200 4125);
DISPLAY INVISIBLE (-2200 4125);
FORCEPROP 2 LAST CDS_LOCATION C2T38
J 0
(-2200 4100);
DISPLAY 0.617021 (-2200 4100);
PAINT AQUA (-2200 4100);
DISPLAY INVISIBLE (-2200 4100);
FORCEADD GND..1
(-1900 3650);
FORCEPROP 3 LASTPIN (-1900 3700) SIG_NAME GND\g
J 0
(-1890 3710);
DISPLAY 0.659574 (-1890 3710);
PAINT MONO (-1890 3710);
DISPLAY INVISIBLE (-1890 3710);
FORCEPROP 1 LAST HDL_POWER GND
J 0
(-1900 3800);
PAINT GREEN (-1900 3800);
DISPLAY INVISIBLE (-1900 3800);
FORCEPROP 1 LAST BODY_TYPE PLUMBING
J 0
(-1945 3607);
DISPLAY 0.340426 (-1945 3607);
PAINT GREEN (-1945 3607);
DISPLAY INVISIBLE (-1945 3607);
FORCEPROP 1 LAST VOLTAGE 0.0V
J 0
(-1945 3607);
DISPLAY 0.340426 (-1945 3607);
PAINT SKYBLUE (-1945 3607);
DISPLAY INVISIBLE (-1945 3607);
FORCEPROP 2 LAST CDS_LIB mstr_symbols
J 0
(-1900 3650);
DISPLAY 2.127660 (-1900 3650);
PAINT ORANGE (-1900 3650);
DISPLAY INVISIBLE (-1900 3650);
FORCEPROP 1 LAST SIZE 1B
J 0
(-1825 3600);
DISPLAY 1.127660 (-1825 3600);
PAINT GREEN (-1825 3600);
DISPLAY INVISIBLE (-1825 3600);
FORCEPROP 2 LAST BOM_COST SM_CONTROLLER
J 0
(-2350 3725);
DISPLAY 1.617021 (-2350 3725);
PAINT WHITE (-2350 3725);
DISPLAY INVISIBLE (-2350 3725);
FORCEPROP 1 LAST PATH I98
J 0
(-1825 3650);
DISPLAY 0.872340 (-1825 3650);
PAINT AQUA (-1825 3650);
DISPLAY INVISIBLE (-1825 3650);
FORCEPROP 2 LAST ROOM SYS_CLOCK
J 0
(-2225 3725);
DISPLAY 1.127660 (-2225 3725);
PAINT WHITE (-2225 3725);
DISPLAY INVISIBLE (-2225 3725);
FORCEADD CAP_A..1
(-2625 4000);
FORCEPROP 1 LAST MATERIAL X7R
J 0
(-2575 3900);
DISPLAY 0.617021 (-2575 3900);
PAINT SKYBLUE (-2575 3900);
FORCEPROP 1 LAST VALUE 0.01UF
J 0
(-2575 4050);
DISPLAY 0.617021 (-2575 4050);
PAINT SKYBLUE (-2575 4050);
FORCEPROP 1 LAST VOLTAGE 25V
J 0
(-2575 4000);
DISPLAY 0.617021 (-2575 4000);
PAINT SKYBLUE (-2575 4000);
FORCEPROP 1 LASTPIN (-2625 3900) $PN 2
J 0
(-2615 3880);
DISPLAY 0.617021 (-2615 3880);
PAINT WHITE (-2615 3880);
FORCEPROP 1 LAST TOLERANCE 10%
J 0
(-2575 3950);
DISPLAY 0.617021 (-2575 3950);
PAINT SKYBLUE (-2575 3950);
FORCEPROP 1 LASTPIN (-2625 4100) $PN 1
J 0
(-2615 4080);
DISPLAY 0.617021 (-2615 4080);
PAINT WHITE (-2615 4080);
FORCEPROP 1 LAST PACK_TYPE 0402V
J 0
(-2575 3800);
DISPLAY 0.617021 (-2575 3800);
PAINT SKYBLUE (-2575 3800);
FORCEPROP 1 LAST LOCATION C2T37
J 0
(-2575 4100);
DISPLAY 0.617021 (-2575 4100);
PAINT AQUA (-2575 4100);
FORCEPROP 1 LAST PART_NUMBER A36096-045
J 0
(-2575 3850);
DISPLAY 0.617021 (-2575 3850);
PAINT BLUE (-2575 3850);
FORCEPROP 2 LAST ROOM SYS_CLOCK
J 0
(-2575 4150);
DISPLAY 1.127660 (-2575 4150);
PAINT WHITE (-2575 4150);
DISPLAY INVISIBLE (-2575 4150);
FORCEPROP 1 LAST PATH I99
J 0
(-2575 4150);
DISPLAY 0.978723 (-2575 4150);
PAINT WHITE (-2575 4150);
DISPLAY INVISIBLE (-2575 4150);
FORCEPROP 2 LAST $SEC 1
J 0
(-2575 4200);
DISPLAY 1.510638 (-2575 4200);
PAINT MONO (-2575 4200);
DISPLAY INVISIBLE (-2575 4200);
FORCEPROP 2 LAST CDS_SEC 1
J 0
(-2575 4200);
DISPLAY 2.276596 (-2575 4200);
PAINT ORANGE (-2575 4200);
DISPLAY INVISIBLE (-2575 4200);
FORCEPROP 2 LAST CDS_LIB dev_discrete
J 0
(-2625 4000);
PAINT ORANGE (-2625 4000);
DISPLAY INVISIBLE (-2625 4000);
FORCEPROP 2 LAST BOM_COST SM_CONTROLLER
J 0
(-2575 4125);
DISPLAY 1.617021 (-2575 4125);
PAINT WHITE (-2575 4125);
DISPLAY INVISIBLE (-2575 4125);
FORCEPROP 2 LAST CDS_LOCATION C2T37
J 0
(-2575 4100);
DISPLAY 0.617021 (-2575 4100);
PAINT AQUA (-2575 4100);
DISPLAY INVISIBLE (-2575 4100);
FORCEADD CAD_NOTE..1
(-7900 350);
FORCEPROP 0 LAST L1 PLACE CAPS CLOSE TO CK-MNG+ PINS
J 0
(-8050 225);
DISPLAY 1.170213 (-8050 225);
PAINT WHITE (-8050 225);
FORCEPROP 1 LAST COMMENT_BODY TRUE
J 0
(-7875 450);
DISPLAY 2.212766 (-7875 450);
PAINT PEACH (-7875 450);
DISPLAY INVISIBLE (-7875 450);
FORCEPROP 2 LAST CDS_LIB mstr_symbols
J 0
(-7900 350);
DISPLAY 1.617021 (-7900 350);
PAINT WHITE (-7900 350);
DISPLAY INVISIBLE (-7900 350);
FORCEADD INTEL_CORP_BPAGE..1
(-1025 -350);
FORCEPROP 1 LAST CDS_CON_LAST_MODIFIED Fri Jun 16 17:48:40 2017
J 0
(-2450 -25);
DISPLAY 0.489362 (-2450 -25);
PAINT GREEN (-2450 -25);
DISPLAY INVISIBLE (-2450 -25);
FORCEPROP 1 LAST CUSTOM_TXT_CDS <CURRENT_DESIGN_SHEET> OF <TOTAL_DESIGN_SHEETS>
J 0
(-1525 -325);
PAINT ORANGE (-1525 -325);
FORCEPROP 2 LAST CUSTOM_TXT_CDS <XR_PAGE_TITLE>
J 0
(-8915 4900);
DISPLAY 0.638298 (-8915 4900);
PAINT PINK (-8915 4900);
DISPLAY INVISIBLE (-8915 4900);
FORCEPROP 2 LAST CUSTOM_TXT_CDS <CON_LAST_MODIFIED>
J 0
(-5025 -250);
DISPLAY 1.255319 (-5025 -250);
PAINT ORANGE (-5025 -250);
FORCEPROP 1 LAST SCH_TITLE CKMNG+
J 0
(-8925 -250);
DISPLAY 1.212766 (-8925 -250);
PAINT GREEN (-8925 -250);
FORCEPROP 1 LAST COMMENT_BODY TRUE
J 0
(-1013 -338);
DISPLAY 0.234043 (-1013 -338);
PAINT GREEN (-1013 -338);
DISPLAY INVISIBLE (-1013 -338);
FORCEPROP 2 LAST CDS_LIB mstr_symbols
J 0
(-1025 -350);
DISPLAY 0.489362 (-1025 -350);
PAINT ORANGE (-1025 -350);
DISPLAY INVISIBLE (-1025 -350);
FORCEPROP 2 LAST PAGE_BORDER TRUE
J 0
(-8915 4900);
DISPLAY 0.425532 (-8915 4900);
PAINT PINK (-8915 4900);
DISPLAY INVISIBLE (-8915 4900);
FORCEPROP 2 LAST CDS_XR_PAGE_TITLE CR-101 : @BASEBOARD_FAB2_LIB.BASEBOARD_FAB2(SCH_1):PAGE101
J 0
(-8915 4900);
DISPLAY 0.638298 (-8915 4900);
PAINT PINK (-8915 4900);
DISPLAY INVISIBLE (-8915 4900);
FORCEADD CAD_NOTE..1
(-7950 3425);
FORCEPROP 0 LAST L1 10UF CAP AND 0.1UF CAP SHOULD BE SEPARATED BY 250MILS
J 0
(-8100 3300);
DISPLAY 0.744681 (-8100 3300);
PAINT WHITE (-8100 3300);
FORCEPROP 0 LAST L2 PLACE 10UF CAP CLOSE TO FERRITE BEAD
J 0
(-8100 3250);
DISPLAY 0.744681 (-8100 3250);
PAINT WHITE (-8100 3250);
FORCEPROP 0 LAST L3 PLACE ALL 0.1UF NEAR CHIP PIN
J 0
(-8100 3200);
DISPLAY 0.744681 (-8100 3200);
PAINT WHITE (-8100 3200);
FORCEPROP 0 LAST L4 CURRENT SHOULD FLOW THROUGH 10UF CAP PAD
J 0
(-8100 3150);
DISPLAY 0.744681 (-8100 3150);
PAINT WHITE (-8100 3150);
FORCEPROP 1 LAST COMMENT_BODY TRUE
J 0
(-7925 3525);
DISPLAY 2.212766 (-7925 3525);
PAINT PEACH (-7925 3525);
DISPLAY INVISIBLE (-7925 3525);
FORCEPROP 2 LAST CDS_LIB mstr_symbols
J 0
(-7950 3425);
DISPLAY 1.617021 (-7950 3425);
PAINT WHITE (-7950 3425);
DISPLAY INVISIBLE (-7950 3425);
FORCEADD CAD_NOTE..1
(-3675 3075);
FORCEPROP 0 LAST L1 PLACE SOURCE TERM RES WITHIN 1 INCH OF CKMNG+
J 0
(-3825 2950);
DISPLAY 1.170213 (-3825 2950);
PAINT WHITE (-3825 2950);
FORCEPROP 1 LAST COMMENT_BODY TRUE
J 0
(-3650 3175);
DISPLAY 1.595745 (-3650 3175);
PAINT PEACH (-3650 3175);
DISPLAY INVISIBLE (-3650 3175);
FORCEPROP 2 LAST CDS_LIB mstr_symbols
J 0
(-3675 3075);
DISPLAY 1.617021 (-3675 3075);
PAINT MONO (-3675 3075);
DISPLAY INVISIBLE (-3675 3075);
FORCEADD CAD_NOTE..1
(-3625 3525);
FORCEPROP 0 LAST L1 PLACE 0.01UF NEAR CHIP PIN
J 0
(-3775 3400);
DISPLAY 1.170213 (-3775 3400);
PAINT WHITE (-3775 3400);
FORCEPROP 1 LAST COMMENT_BODY TRUE
J 0
(-3600 3625);
DISPLAY 2.212766 (-3600 3625);
PAINT PEACH (-3600 3625);
DISPLAY INVISIBLE (-3600 3625);
FORCEPROP 2 LAST CDS_LIB mstr_symbols
J 0
(-3625 3525);
DISPLAY 1.617021 (-3625 3525);
PAINT WHITE (-3625 3525);
DISPLAY INVISIBLE (-3625 3525);
FORCEADD DNS..2
(-1895 3995);
PAINT RED (-1895 3995);
FORCEPROP 1 LAST COMMENT_BODY TRUE
R 1
J 0
(-1820 3770);
DISPLAY 0.872340 (-1820 3770);
PAINT GREEN (-1820 3770);
DISPLAY INVISIBLE (-1820 3770);
FORCEPROP 2 LAST CDS_LIB mstr_misc
J 0
(-1895 3995);
PAINT ORANGE (-1895 3995);
DISPLAY INVISIBLE (-1895 3995);
WIRE 16 -1 (-4500 4300)(-4500 4150);
WIRE 16 -1 (-4500 4150)(-4425 4150);
WIRE 16 -1 (-3625 4150)(-3625 4225);
FORCEPROP 0 LAST VOLTAGE +3.3V
J 0
(-3800 4200);
DISPLAY 1.021277 (-3800 4200);
PAINT SKYBLUE (-3800 4200);
DISPLAY INVISIBLE (-3800 4200);
WIRE 16 -1 (-3625 4150)(-4050 4150);
WIRE 16 -1 (-3625 4025)(-3625 4150);
WIRE 16 -1 (-4050 4025)(-4050 4150);
WIRE 16 -1 (-4050 4150)(-4225 4150);
WIRE 16 -1 (-3000 4200)(-3000 4325);
WIRE 16 -1 (-2925 4200)(-3000 4200);
WIRE 16 -1 (-1900 4300)(-1900 4200);
FORCEPROP 0 LAST VOLTAGE +3.3V
J 0
(-1900 4325);
DISPLAY 1.021277 (-1900 4325);
PAINT SKYBLUE (-1900 4325);
DISPLAY INVISIBLE (-1900 4325);
WIRE 16 -1 (-1900 4200)(-2250 4200);
WIRE 16 -1 (-1900 4200)(-1900 4100);
WIRE 16 -1 (-2625 4200)(-2250 4200);
WIRE 16 -1 (-2250 4100)(-2250 4200);
WIRE 16 -1 (-2725 4200)(-2625 4200);
WIRE 16 -1 (-2625 4100)(-2625 4200);
WIRE 16 -1 (-5150 3750)(-5150 3700);
WIRE 16 -1 (-5150 3750)(-5550 3750);
WIRE 16 -1 (-5150 3750)(-5150 3875);
WIRE 16 -1 (-5550 3875)(-5550 3750);
WIRE 16 -1 (-6600 3675)(-6600 3725);
WIRE 16 -1 (-6600 3725)(-6900 3725);
WIRE 16 -1 (-6600 3875)(-6600 3725);
WIRE 16 -1 (-6900 3725)(-7300 3725);
WIRE 16 -1 (-6900 3725)(-6900 3875);
WIRE 16 -1 (-7300 3725)(-7600 3725);
WIRE 16 -1 (-7300 3725)(-7300 3875);
WIRE 16 -1 (-7900 3725)(-7600 3725);
WIRE 16 -1 (-7600 3725)(-7600 3875);
WIRE 16 -1 (-7900 3725)(-7900 3875);
WIRE 16 -1 (-8475 4300)(-8475 4125);
WIRE 16 -1 (-8225 4125)(-8475 4125);
WIRE 16 -1 (-8475 4125)(-8475 4050);
WIRE 16 -1 (-6600 4125)(-6600 4225);
WIRE 16 -1 (-6600 4125)(-6900 4125);
WIRE 16 -1 (-6600 4075)(-6600 4125);
WIRE 16 -1 (-6900 4125)(-7300 4125);
WIRE 16 -1 (-6900 4125)(-6900 4075);
WIRE 16 -1 (-7300 4125)(-7600 4125);
WIRE 16 -1 (-7300 4125)(-7300 4075);
WIRE 16 -1 (-7600 4125)(-7900 4125);
WIRE 16 -1 (-7600 4075)(-7600 4125);
WIRE 16 -1 (-8025 4125)(-7900 4125);
WIRE 16 -1 (-7900 4125)(-7900 4075);
WIRE 16 -1 (-6100 4300)(-6100 4150);
WIRE 16 -1 (-5925 4150)(-6100 4150);
WIRE 16 -1 (-6300 2550)(-6300 3175);
WIRE 16 -1 (-6300 2550)(-6150 2550);
WIRE 16 -1 (-6600 2975)(-6600 2450);
WIRE 16 -1 (-6600 2400)(-6600 2450);
WIRE 16 -1 (-6600 2450)(-6150 2450);
WIRE 16 -1 (-6150 2400)(-6600 2400);
WIRE 16 -1 (-5150 4150)(-5150 4250);
WIRE 16 -1 (-5150 4150)(-5550 4150);
WIRE 16 -1 (-5150 4075)(-5150 4150);
WIRE 16 -1 (-5550 4075)(-5550 4150);
WIRE 16 -1 (-5725 4150)(-5550 4150);
WIRE 16 -1 (-7000 2300)(-7000 2475);
WIRE 16 -1 (-7000 2300)(-7000 2250);
WIRE 16 -1 (-6150 2300)(-7000 2300);
FORCEPROP 0 LAST VOLTAGE +3.3V
J 0
(-6975 2375);
DISPLAY 1.021277 (-6975 2375);
PAINT SKYBLUE (-6975 2375);
DISPLAY INVISIBLE (-6975 2375);
WIRE 16 -1 (-7000 2250)(-7000 2150);
WIRE 16 -1 (-6150 2250)(-7000 2250);
WIRE 16 -1 (-7000 2150)(-7000 2100);
WIRE 16 -1 (-6150 2150)(-7000 2150);
WIRE 16 -1 (-7000 2100)(-6150 2100);
WIRE 16 -1 (-7500 2350)(-7500 2050);
WIRE 16 -1 (-6150 2050)(-7500 2050);
FORCEPROP 0 LAST VOLTAGE +3.3V
J 0
(-7025 2125);
DISPLAY 1.021277 (-7025 2125);
PAINT SKYBLUE (-7025 2125);
DISPLAY INVISIBLE (-7025 2125);
WIRE 16 -1 (-8325 1300)(-8325 1175);
WIRE 16 -1 (-4375 2850)(-4375 2900);
WIRE 16 -1 (-4650 1000)(-4650 850);
WIRE 16 -1 (-4650 1050)(-4650 1000);
WIRE 16 -1 (-4850 1000)(-4650 1000);
WIRE 16 -1 (-4650 1100)(-4650 1050);
WIRE 16 -1 (-4850 1050)(-4650 1050);
WIRE 16 -1 (-4650 1200)(-4650 1100);
WIRE 16 -1 (-4850 1100)(-4650 1100);
WIRE 16 -1 (-4650 1250)(-4650 1200);
WIRE 16 -1 (-4850 1200)(-4650 1200);
WIRE 16 -1 (-4650 1300)(-4650 1250);
WIRE 16 -1 (-4850 1250)(-4650 1250);
WIRE 16 -1 (-4650 1400)(-4650 1300);
WIRE 16 -1 (-4850 1300)(-4650 1300);
WIRE 16 -1 (-4650 1450)(-4650 1400);
WIRE 16 -1 (-4850 1400)(-4650 1400);
WIRE 16 -1 (-4650 1550)(-4650 1450);
WIRE 16 -1 (-4850 1450)(-4650 1450);
WIRE 16 -1 (-4850 1550)(-4650 1550);
WIRE 16 -1 (-7350 550)(-7350 450);
WIRE 16 -1 (-7350 550)(-7150 550);
WIRE 16 -1 (-7600 550)(-7350 550);
WIRE 16 -1 (-7600 550)(-7600 700);
WIRE 16 -1 (-7150 700)(-7150 550);
WIRE 16 -1 (-8475 3850)(-8475 3700);
WIRE 16 -1 (-7925 1125)(-7925 950);
WIRE 16 -1 (-3625 3700)(-3625 3675);
WIRE 16 -1 (-3625 3700)(-4050 3700);
WIRE 16 -1 (-3625 3700)(-3625 3825);
WIRE 16 -1 (-4050 3825)(-4050 3700);
WIRE 16 -1 (-1900 3750)(-1900 3700);
WIRE 16 -1 (-1900 3750)(-2250 3750);
WIRE 16 -1 (-1900 3900)(-1900 3750);
WIRE 16 -1 (-2625 3750)(-2250 3750);
WIRE 16 -1 (-2250 3750)(-2250 3900);
WIRE 16 -1 (-2625 3900)(-2625 3750);
WIRE 3 682 (-3400 1750)(-2600 1750);
WIRE 3 682 (-3400 2250)(-3400 1750);
WIRE 3 682 (-2600 1750)(-2600 2250);
WIRE 3 682 (-2600 2250)(-3400 2250);
WIRE 16 -1 (-4850 2450)(-3150 2450);
FORCEPROP 2 LAST SIG_NAME CLK_25M_BMC_R
J 0
(-4750 2460);
DISPLAY 0.617021 (-4750 2460);
PAINT ORANGE (-4750 2460);
FORCEPROP 2 LASTPROP $XRERR UNIQUE?
J 0
(-4990 2460);
DISPLAY 0.638298 (-4990 2460);
PAINT MONO (-4990 2460);
DISPLAY INVISIBLE (-4990 2460);
WIRE 16 -1 (-2950 2450)(-1925 2450);
FORCEPROP 2 LAST SIG_NAME CLK_25M_BMC
J 0
(-2550 2460);
DISPLAY 0.617021 (-2550 2460);
PAINT ORANGE (-2550 2460);
WIRE 16 -1 (-3650 2000)(-3150 2000);
WIRE 16 -1 (-4850 2250)(-3650 2250);
FORCEPROP 2 LAST SIG_NAME CLK_50M_CKMNG_SPRVLLE_R
J 0
(-4750 2260);
DISPLAY 0.617021 (-4750 2260);
PAINT ORANGE (-4750 2260);
FORCEPROP 2 LASTPROP $XRERR UNIQUE?
J 0
(-4990 2260);
DISPLAY 0.638298 (-4990 2260);
PAINT MONO (-4990 2260);
DISPLAY INVISIBLE (-4990 2260);
WIRE 16 -1 (-3650 2250)(-3650 2000);
WIRE 16 -1 (-3700 1850)(-3150 1850);
WIRE 16 -1 (-4850 2200)(-3700 2200);
FORCEPROP 2 LAST SIG_NAME CLK_50M_CKMNG_BMC_2_R
J 0
(-4750 2210);
DISPLAY 0.617021 (-4750 2210);
PAINT ORANGE (-4750 2210);
FORCEPROP 2 LASTPROP $XRERR UNIQUE?
J 0
(-4990 2210);
DISPLAY 0.638298 (-4990 2210);
PAINT MONO (-4990 2210);
DISPLAY INVISIBLE (-4990 2210);
WIRE 16 -1 (-3700 2200)(-3700 1850);
WIRE 16 -1 (-4850 2000)(-4000 2000);
FORCEPROP 2 LAST SIG_NAME TP_CLK_125M
J 0
(-4750 2010);
DISPLAY 0.617021 (-4750 2010);
PAINT ORANGE (-4750 2010);
FORCEPROP 2 LASTPROP $XRERR UNIQUE?
J 0
(-3970 2000);
DISPLAY 0.638298 (-3970 2000);
PAINT MONO (-3970 2000);
DISPLAY INVISIBLE (-3970 2000);
WIRE 16 -1 (-3800 1550)(-3150 1550);
WIRE 16 -1 (-4850 2100)(-3800 2100);
FORCEPROP 0 LAST SIG_NAME CLK_50M_CKMNG_OCP_R
J 0
(-4750 2110);
DISPLAY 0.617021 (-4750 2110);
PAINT ORANGE (-4750 2110);
FORCEPROP 2 LASTPROP $XRERR UNIQUE?
J 0
(-4990 2110);
DISPLAY 0.638298 (-4990 2110);
PAINT MONO (-4990 2110);
DISPLAY INVISIBLE (-4990 2110);
WIRE 16 -1 (-3800 2100)(-3800 1550);
WIRE 16 -1 (-2950 2000)(-1925 2000);
FORCEPROP 2 LAST SIG_NAME CLK_50M_CKMNG_SPRVLLE
J 0
(-2550 2010);
DISPLAY 0.617021 (-2550 2010);
PAINT ORANGE (-2550 2010);
WIRE 16 -1 (-2950 1850)(-1925 1850);
FORCEPROP 2 LAST SIG_NAME CLK_50M_CKMNG_BMC_2
J 0
(-2550 1860);
DISPLAY 0.617021 (-2550 1860);
PAINT ORANGE (-2550 1860);
WIRE 16 -1 (-3750 1700)(-3150 1700);
WIRE 16 -1 (-4850 2150)(-3750 2150);
FORCEPROP 0 LAST SIG_NAME CLK_50M_CKMNG_BMC_1_R
J 0
(-4750 2160);
DISPLAY 0.617021 (-4750 2160);
PAINT ORANGE (-4750 2160);
FORCEPROP 2 LASTPROP $XRERR UNIQUE?
J 0
(-4990 2160);
DISPLAY 0.638298 (-4990 2160);
PAINT MONO (-4990 2160);
DISPLAY INVISIBLE (-4990 2160);
WIRE 16 -1 (-3750 2150)(-3750 1700);
WIRE 16 -1 (-2950 1700)(-1925 1700);
FORCEPROP 2 LAST SIG_NAME CLK_50M_CKMNG_BMC_1
J 0
(-2550 1710);
DISPLAY 0.617021 (-2550 1710);
PAINT ORANGE (-2550 1710);
WIRE 16 -1 (-2950 2150)(-1925 2150);
FORCEPROP 2 LAST SIG_NAME CLK_50M_CKMNG_PCH_10GBE
J 0
(-2550 2160);
DISPLAY 0.617021 (-2550 2160);
PAINT ORANGE (-2550 2160);
WIRE 16 -1 (-2950 1550)(-1925 1550);
FORCEPROP 2 LAST SIG_NAME CLK_50M_CKMNG_OCP
J 0
(-2550 1560);
DISPLAY 0.617021 (-2550 1560);
PAINT ORANGE (-2550 1560);
WIRE 16 -1 (-6250 150)(-7350 150);
FORCEPROP 2 LAST SIG_NAME PWRGD_P3V3_STBY
J 0
(-7360 160);
DISPLAY 0.617021 (-7360 160);
PAINT ORANGE (-7360 160);
WIRE 16 -1 (-6250 1100)(-6250 150);
WIRE 16 -1 (-6250 1100)(-6150 1100);
WIRE 3 682 (-7700 950)(-7700 500);
WIRE 3 682 (-6800 950)(-7700 950);
WIRE 3 682 (-7700 500)(-6800 500);
WIRE 3 682 (-6800 500)(-6800 950);
WIRE 16 -1 (-7250 1050)(-7150 1050);
WIRE 16 -1 (-7150 900)(-7150 1050);
WIRE 16 -1 (-7150 1200)(-7150 1050);
WIRE 16 -1 (-7150 1200)(-6150 1200);
FORCEPROP 2 LAST SIG_NAME XTAL_CK_MNG_IN
J 0
(-6735 1210);
DISPLAY 0.617021 (-6735 1210);
PAINT ORANGE (-6735 1210);
FORCEPROP 2 LASTPROP $XRERR UNIQUE?
J 0
(-6975 1210);
DISPLAY 0.638298 (-6975 1210);
PAINT MONO (-6975 1210);
DISPLAY INVISIBLE (-6975 1210);
WIRE 16 3135 (-6125 850)(-6125 700);
WIRE 16 3135 (-4925 850)(-6125 850);
WIRE 16 3135 (-6125 700)(-4925 700);
WIRE 16 3135 (-4925 700)(-4925 850);
WIRE 16 -1 (-7600 900)(-7600 1050);
WIRE 16 -1 (-7600 1050)(-7450 1050);
WIRE 16 -1 (-7600 1250)(-7600 1050);
WIRE 16 -1 (-7600 1250)(-7025 1250);
FORCEPROP 2 LAST SIG_NAME XTAL_CK_MNG_OUT
J 0
(-7585 1260);
DISPLAY 0.617021 (-7585 1260);
PAINT ORANGE (-7585 1260);
FORCEPROP 2 LASTPROP $XRERR UNIQUE?
J 0
(-7825 1260);
DISPLAY 0.638298 (-7825 1260);
PAINT MONO (-7825 1260);
DISPLAY INVISIBLE (-7825 1260);
WIRE 3 682 (-7000 1300)(-7000 1150);
WIRE 3 682 (-7000 1300)(-6850 1300);
WIRE 3 682 (-7000 1150)(-6850 1150);
WIRE 3 682 (-6850 1150)(-6850 1300);
WIRE 16 -1 (-7925 1450)(-7925 1325);
WIRE 16 -1 (-6400 1450)(-7925 1450);
FORCEPROP 0 LAST SIG_NAME PD_CKMNG_OE
J 0
(-7460 1460);
DISPLAY 0.617021 (-7460 1460);
PAINT ORANGE (-7460 1460);
FORCEPROP 2 LASTPROP $XRERR UNIQUE?
J 0
(-7700 1460);
DISPLAY 0.638298 (-7700 1460);
PAINT MONO (-7700 1460);
DISPLAY INVISIBLE (-7700 1460);
WIRE 16 -1 (-6400 1450)(-6150 1450);
WIRE 16 -1 (-6150 1400)(-6400 1400);
WIRE 16 -1 (-6400 1400)(-6400 1450);
WIRE 16 -1 (-6150 1250)(-6825 1250);
FORCEPROP 2 LAST SIG_NAME XTAL_CK_MNG_OUT_R
J 0
(-6760 1260);
DISPLAY 0.617021 (-6760 1260);
PAINT ORANGE (-6760 1260);
FORCEPROP 2 LASTPROP $XRERR UNIQUE?
J 0
(-7000 1260);
DISPLAY 0.638298 (-7000 1260);
PAINT MONO (-7000 1260);
DISPLAY INVISIBLE (-7000 1260);
WIRE 16 -1 (-3750 2600)(-3150 2600);
WIRE 16 -1 (-3750 2500)(-3750 2600);
WIRE 16 -1 (-4850 2500)(-3750 2500);
FORCEPROP 2 LAST SIG_NAME CLK_25M_CPLD_R
J 0
(-4750 2510);
DISPLAY 0.617021 (-4750 2510);
PAINT ORANGE (-4750 2510);
FORCEPROP 2 LASTPROP $XRERR UNIQUE?
J 0
(-4990 2510);
DISPLAY 0.638298 (-4990 2510);
PAINT MONO (-4990 2510);
DISPLAY INVISIBLE (-4990 2510);
WIRE 16 -1 (-4775 2650)(-4850 2650);
WIRE 16 -1 (-4775 3175)(-4775 2650);
WIRE 16 -1 (-4375 3175)(-4775 3175);
FORCEPROP 2 LAST SIG_NAME A_COMP_CKMNG
J 0
(-4735 3200);
DISPLAY 0.617021 (-4735 3200);
PAINT ORANGE (-4735 3200);
FORCEPROP 2 LASTPROP $XRERR UNIQUE?
J 0
(-4975 3200);
DISPLAY 0.638298 (-4975 3200);
PAINT MONO (-4975 3200);
DISPLAY INVISIBLE (-4975 3200);
WIRE 16 -1 (-4375 3100)(-4375 3175);
WIRE 16 -1 (-6150 1825)(-6150 1900);
WIRE 16 -1 (-7025 1825)(-6150 1825);
FORCEPROP 2 LAST SIG_NAME SMB_HOST_STBY_LVC3_SDA_R4
J 0
(-6960 1835);
DISPLAY 0.617021 (-6960 1835);
PAINT ORANGE (-6960 1835);
FORCEPROP 2 LASTPROP $XRERR UNIQUE?
J 0
(-7200 1835);
DISPLAY 0.638298 (-7200 1835);
PAINT MONO (-7200 1835);
DISPLAY INVISIBLE (-7200 1835);
WIRE 16 -1 (-7025 1950)(-6150 1950);
FORCEPROP 2 LAST SIG_NAME SMB_HOST_STBY_LVC3_SCL_R4
J 0
(-6960 1960);
DISPLAY 0.617021 (-6960 1960);
PAINT ORANGE (-6960 1960);
FORCEPROP 2 LASTPROP $XRERR UNIQUE?
J 0
(-7200 1960);
DISPLAY 0.638298 (-7200 1960);
PAINT MONO (-7200 1960);
DISPLAY INVISIBLE (-7200 1960);
WIRE 16 -1 (-7225 1950)(-8075 1950);
FORCEPROP 2 LAST SIG_NAME SMB_HOST_STBY_LVC3_SCL
J 0
(-8085 1960);
DISPLAY 0.617021 (-8085 1960);
PAINT ORANGE (-8085 1960);
WIRE 16 -1 (-8075 1825)(-7225 1825);
FORCEPROP 2 LAST SIG_NAME SMB_HOST_STBY_LVC3_SDA
J 0
(-8085 1835);
DISPLAY 0.617021 (-8085 1835);
PAINT ORANGE (-8085 1835);
WIRE 3 682 (-8400 1200)(-8400 1650);
WIRE 3 682 (-8050 1200)(-8400 1200);
WIRE 3 682 (-8400 1650)(-8050 1650);
WIRE 3 682 (-8050 1650)(-8050 1200);
WIRE 3 682 (-7250 2000)(-7050 2000);
WIRE 3 682 (-7050 1750)(-7050 2000);
WIRE 3 682 (-7250 2000)(-7250 1750);
WIRE 3 682 (-7250 1750)(-7050 1750);
WIRE 16 -1 (-4850 1950)(-4000 1950);
FORCEPROP 2 LAST SIG_NAME TP_CLK_125M_BMCA
J 0
(-4750 1960);
DISPLAY 0.617021 (-4750 1960);
PAINT ORANGE (-4750 1960);
FORCEPROP 2 LASTPROP $XRERR UNIQUE?
J 0
(-3970 1950);
DISPLAY 0.638298 (-3970 1950);
PAINT MONO (-3970 1950);
DISPLAY INVISIBLE (-3970 1950);
WIRE 16 -1 (-4850 2350)(-4000 2350);
FORCEPROP 2 LAST SIG_NAME TP_CLK5_50M_CKMNG
J 0
(-4750 2360);
DISPLAY 0.617021 (-4750 2360);
PAINT ORANGE (-4750 2360);
FORCEPROP 2 LASTPROP $XRERR UNIQUE?
J 0
(-3970 2350);
DISPLAY 0.638298 (-3970 2350);
PAINT MONO (-3970 2350);
DISPLAY INVISIBLE (-3970 2350);
WIRE 16 -1 (-8325 1600)(-8325 1500);
WIRE 16 -1 (-8325 1600)(-6150 1600);
FORCEPROP 2 LAST SIG_NAME PU_33P_33M_SMBADR
J 0
(-6885 1610);
DISPLAY 0.617021 (-6885 1610);
PAINT ORANGE (-6885 1610);
FORCEPROP 2 LASTPROP $XRERR UNIQUE?
J 0
(-7125 1610);
DISPLAY 0.638298 (-7125 1610);
PAINT MONO (-7125 1610);
DISPLAY INVISIBLE (-7125 1610);
WIRE 16 -1 (-3800 2775)(-3150 2775);
WIRE 16 -1 (-3800 2600)(-3800 2775);
WIRE 16 -1 (-4850 2600)(-3800 2600);
FORCEPROP 2 LAST SIG_NAME CLK_32K_SUSCLK_PLD_R
J 0
(-4750 2610);
DISPLAY 0.617021 (-4750 2610);
PAINT ORANGE (-4750 2610);
FORCEPROP 2 LASTPROP $XRERR UNIQUE?
J 0
(-4990 2610);
DISPLAY 0.638298 (-4990 2610);
PAINT MONO (-4990 2610);
DISPLAY INVISIBLE (-4990 2610);
WIRE 16 -1 (-3600 2150)(-3150 2150);
WIRE 16 -1 (-3600 2300)(-3600 2150);
WIRE 16 -1 (-4850 2300)(-3600 2300);
FORCEPROP 2 LAST SIG_NAME CLK_50M_CKMNG_PCH_10GBE_R
J 0
(-4750 2310);
DISPLAY 0.617021 (-4750 2310);
PAINT ORANGE (-4750 2310);
FORCEPROP 2 LASTPROP $XRERR UNIQUE?
J 0
(-4990 2310);
DISPLAY 0.638298 (-4990 2310);
PAINT MONO (-4990 2310);
DISPLAY INVISIBLE (-4990 2310);
WIRE 16 -1 (-1925 2600)(-2950 2600);
WIRE 16 -1 (-2950 2775)(-1925 2775);
FORCEPROP 2 LAST SIG_NAME CLK_32K_SUSCLK_PLD
J 0
(-2550 2785);
DISPLAY 0.617021 (-2550 2785);
PAINT ORANGE (-2550 2785);
WIRE 3 682 (-3400 2700)(-3400 2850);
WIRE 3 682 (-2600 2700)(-3400 2700);
WIRE 3 682 (-3400 2850)(-2600 2850);
WIRE 3 682 (-2600 2850)(-2600 2700);
WIRE 16 -1 (-4850 1850)(-4000 1850);
FORCEPROP 2 LAST SIG_NAME TP_CLK_96M_CKMNG_N
J 0
(-4750 1860);
DISPLAY 0.617021 (-4750 1860);
PAINT ORANGE (-4750 1860);
FORCEPROP 2 LASTPROP $XRERR UNIQUE?
J 0
(-3970 1850);
DISPLAY 0.638298 (-3970 1850);
PAINT MONO (-3970 1850);
DISPLAY INVISIBLE (-3970 1850);
WIRE 16 -1 (-4850 1800)(-4000 1800);
FORCEPROP 2 LAST SIG_NAME TP_CLK_96M_CKMNG_P
J 0
(-4750 1810);
DISPLAY 0.617021 (-4750 1810);
PAINT ORANGE (-4750 1810);
FORCEPROP 2 LASTPROP $XRERR UNIQUE?
J 0
(-3970 1800);
DISPLAY 0.638298 (-3970 1800);
PAINT MONO (-3970 1800);
DISPLAY INVISIBLE (-3970 1800);
WIRE 16 -1 (-4850 1700)(-4000 1700);
FORCEPROP 2 LAST SIG_NAME TP_CLK_100M_R_DN
J 0
(-4750 1710);
DISPLAY 0.617021 (-4750 1710);
PAINT ORANGE (-4750 1710);
FORCEPROP 2 LASTPROP $XRERR UNIQUE?
J 0
(-3970 1700);
DISPLAY 0.638298 (-3970 1700);
PAINT MONO (-3970 1700);
DISPLAY INVISIBLE (-3970 1700);
WIRE 16 -1 (-4850 1650)(-4000 1650);
FORCEPROP 2 LAST SIG_NAME TP_CLK_100M_R_DP
J 0
(-4750 1660);
DISPLAY 0.617021 (-4750 1660);
PAINT ORANGE (-4750 1660);
FORCEPROP 2 LASTPROP $XRERR UNIQUE?
J 0
(-3970 1650);
DISPLAY 0.638298 (-3970 1650);
PAINT MONO (-3970 1650);
DISPLAY INVISIBLE (-3970 1650);
WIRE 3 682 (-1550 3800)(-2000 3800);
WIRE 3 682 (-1550 4150)(-1550 3800);
WIRE 3 682 (-2000 3800)(-2000 4150);
WIRE 3 682 (-2000 4150)(-1550 4150);
DOT 1 (-4650 1250);
DOT 1 (-4650 1400);
DOT 1 (-4650 1450);
DOT 1 (-6600 3725);
DOT 1 (-7600 3725);
DOT 1 (-8475 4125);
DOT 1 (-7900 4125);
DOT 1 (-7600 4125);
DOT 1 (-6600 4125);
DOT 1 (-5150 4150);
DOT 1 (-5550 4150);
DOT 1 (-5150 3750);
DOT 1 (-2250 4200);
DOT 1 (-2625 4200);
DOT 1 (-2250 3750);
DOT 1 (-3625 4150);
DOT 1 (-4050 4150);
DOT 1 (-3625 3700);
DOT 1 (-6900 3725);
DOT 1 (-7300 3725);
DOT 1 (-6900 4125);
DOT 1 (-1900 3750);
DOT 1 (-7000 2300);
DOT 1 (-7000 2250);
DOT 1 (-6600 2450);
DOT 1 (-4650 1000);
DOT 1 (-4650 1050);
DOT 1 (-4650 1100);
DOT 1 (-4650 1200);
DOT 1 (-4650 1300);
DOT 1 (-7000 2150);
DOT 1 (-6400 1450);
DOT 1 (-1900 4200);
DOT 1 (-7300 4125);
DOT 1 (-7600 1050);
DOT 1 (-7150 1050);
DOT 1 (-7350 550);
FORCENOTE
TP FAB1 CHANGE RESISTANCE 0216
(-3400 2275) 0;
DISPLAY LEFT (-3400 2275);
DISPLAY 1.021277 (-3400 2275);
PAINT RED (-3400 2275);
FORCENOTE
TP FAB1 CHANGE RESISTANCE 0216
(-3400 2875) 0;
DISPLAY LEFT (-3400 2875);
DISPLAY 1.021277 (-3400 2875);
PAINT RED (-3400 2875);
FORCENOTE
ROOM=SYS_CLOCK
(-8966 -128) 0;
DISPLAY LEFT (-8966 -128);
PAINT PURPLE (-8966 -128);
FORCENOTE
CKMNG+
(-5700 2925) 0;
DISPLAY LEFT (-5700 2925);
DISPLAY 1.595745 (-5700 2925);
PAINT PURPLE (-5700 2925);
FORCENOTE
TP FAB1 ADD RES 0215
(-8700 1675) 0;
DISPLAY LEFT (-8700 1675);
DISPLAY 1.021277 (-8700 1675);
PAINT RED (-8700 1675);
FORCENOTE
TP FAB1 ADD RES 0215
(-7550 1675) 0;
DISPLAY LEFT (-7550 1675);
DISPLAY 1.021277 (-7550 1675);
PAINT RED (-7550 1675);
FORCENOTE
TP FAB1 ADD CAP 0215
(-1850 3725) 0;
DISPLAY LEFT (-1850 3725);
DISPLAY 1.021277 (-1850 3725);
PAINT RED (-1850 3725);
FORCENOTE
SMBUS ADDRESS =0XD0
(-6075 750) 0;
DISPLAY LEFT (-6075 750);
DISPLAY 1.170213 (-6075 750);
PAINT PURPLE (-6075 750);
FORCENOTE
TP FAB3 CHANGE CAP 0823
(-7300 450) 0;
DISPLAY LEFT (-7300 450);
DISPLAY 0.638298 (-7300 450);
PAINT RED (-7300 450);
FORCENOTE
TP FAB1 ADD RES 0215
(-7075 1075) 0;
DISPLAY LEFT (-7075 1075);
DISPLAY 1.021277 (-7075 1075);
PAINT RED (-7075 1075);
FORCENOTE
$CDS_IMAGE|ICS9FGP204 I2C.jpg|1548|708
(-3450 675) 0;
DISPLAY LEFT (-3450 675);
QUIT
